FILE_TYPE = MACRO_DRAWING;
SET COLOR_WIRE YELLOW;
SET COLOR_PROP ORANGE;
SET COLOR_DOT WHITE;
SET COLOR_ARC YELLOW;
SET COLOR_BODY GREEN;
SET COLOR_NOTE PURPLE;
SET PROP_DISPLAY VALUE;
SET PAGE_NUMBER P336;
FORCEADD 74CBTLV3126PW..1
R 2
(-225 6700);
FORCEPROP 1 LAST LOCATION U67
J 2
(23 7158);
DISPLAY 0.723404 (23 7158);
PAINT GREEN (23 7158);
FORCEPROP 2 LAST $SEC 1
J 0
(0 7300);
DISPLAY 0.680851 (0 7300);
PAINT MONO (0 7300);
DISPLAY INVISIBLE (0 7300);
FORCEPROP 2 LAST CDS_SEC 1
J 0
(0 7300);
DISPLAY 1.021277 (0 7300);
DISPLAY INVISIBLE (0 7300);
FORCEPROP 2 LASTPIN (175 6450) $PN 2
J 0
(185 6460);
DISPLAY 0.808511 (185 6460);
FORCEPROP 2 LASTPIN (-625 6450) $PN 3
J 2
(-635 6460);
DISPLAY 0.808511 (-635 6460);
FORCEPROP 2 LASTPIN (175 6400) $PN 1
J 0
(185 6410);
DISPLAY 0.808511 (185 6410);
FORCEPROP 2 LASTPIN (175 6600) $PN 5
J 0
(185 6610);
DISPLAY 0.808511 (185 6610);
FORCEPROP 2 LASTPIN (-625 6600) $PN 6
J 2
(-635 6610);
DISPLAY 0.808511 (-635 6610);
FORCEPROP 2 LASTPIN (175 6550) $PN 4
J 0
(185 6560);
DISPLAY 0.808511 (185 6560);
FORCEPROP 2 LASTPIN (175 6750) $PN 9
J 0
(185 6760);
DISPLAY 0.808511 (185 6760);
FORCEPROP 2 LASTPIN (-625 6750) $PN 8
J 2
(-635 6760);
DISPLAY 0.808511 (-635 6760);
FORCEPROP 2 LASTPIN (175 6700) $PN 10
J 0
(185 6710);
DISPLAY 0.808511 (185 6710);
FORCEPROP 2 LASTPIN (175 6900) $PN 12
J 0
(185 6910);
DISPLAY 0.808511 (185 6910);
FORCEPROP 2 LASTPIN (-625 6900) $PN 11
J 2
(-635 6910);
DISPLAY 0.808511 (-635 6910);
FORCEPROP 2 LASTPIN (175 6850) $PN 13
J 0
(185 6860);
DISPLAY 0.808511 (185 6860);
FORCEPROP 2 LASTPIN (-625 6400) $PN 7
J 2
(-635 6410);
DISPLAY 0.808511 (-635 6410);
FORCEPROP 2 LASTPIN (-625 6950) $PN 14
J 2
(-635 6960);
DISPLAY 0.808511 (-635 6960);
FORCEPROP 2 LAST PART_TYPE SMLF
J 2
(0 7250);
DISPLAY 1.021277 (0 7250);
FORCEPROP 2 LAST VALUE 74CBTLV3126PW
J 2
(0 7200);
DISPLAY 1.021277 (0 7200);
FORCEPROP 1 LAST MATERIAL IC
J 2
(23 7053);
DISPLAY 0.723404 (23 7053);
PAINT GREEN (23 7053);
FORCEPROP 2 LAST CDS_LIB pure_quanta
J 2
(-225 6700);
PAINT MONO (-225 6700);
DISPLAY INVISIBLE (-225 6700);
FORCEPROP 1 LAST NEEDS_NO_SIZE TRUE
J 2
(-475 6390);
DISPLAY 0.723404 (-475 6390);
PAINT GREEN (-475 6390);
DISPLAY INVISIBLE (-475 6390);
FORCEPROP 1 LAST CDS_LMAN_SYM_OUTLINE -250,350,250,-350
J 2
(-225 6700);
DISPLAY 0.468085 (-225 6700);
PAINT GREEN (-225 6700);
DISPLAY INVISIBLE (-225 6700);
FORCEPROP 1 LAST PATH I1
J 2
(-475 6350);
DISPLAY 0.723404 (-475 6350);
PAINT GREEN (-475 6350);
DISPLAY INVISIBLE (-475 6350);
FORCEPROP 1 LAST PART_NUMBER AL003126K08
J 2
(23 7108);
DISPLAY 0.723404 (23 7108);
PAINT GREEN (23 7108);
DISPLAY INVISIBLE (23 7108);
FORCEADD Q_RES..1
(1450 6600);
FORCEPROP 1 LAST LOCATION R72
J 0
(1150 6600);
DISPLAY 0.702128 (1150 6600);
PAINT YELLOW (1150 6600);
FORCEPROP 0 LAST $SEC 1
J 0
(1525 6650);
DISPLAY INVISIBLE (1525 6650);
FORCEPROP 0 LAST CDS_SEC 1
J 0
(1525 6650);
DISPLAY INVISIBLE (1525 6650);
FORCEPROP 1 LASTPIN (1350 6600) $PN 1
J 0
(1362 6612);
DISPLAY 0.808511 (1362 6612);
PAINT WHITE (1362 6612);
DISPLAY INVISIBLE (1362 6612);
FORCEPROP 1 LASTPIN (1550 6600) $PN 2
J 0
(1512 6612);
DISPLAY 0.808511 (1512 6612);
PAINT WHITE (1512 6612);
DISPLAY INVISIBLE (1512 6612);
FORCEPROP 1 LAST VALUE 22
J 2
(1400 6625);
DISPLAY 0.510638 (1400 6625);
PAINT SKYBLUE (1400 6625);
FORCEPROP 1 LAST MATERIAL CHIP
J 0
(1525 6625);
DISPLAY 0.510638 (1525 6625);
PAINT SKYBLUE (1525 6625);
FORCEPROP 1 LAST WATTAGE 1/16W
J 2
(1425 6450);
DISPLAY 0.510638 (1425 6450);
PAINT SKYBLUE (1425 6450);
DISPLAY INVISIBLE (1425 6450);
FORCEPROP 1 LAST TOLERANCE 1%
J 0
(1450 6500);
DISPLAY 0.510638 (1450 6500);
PAINT SKYBLUE (1450 6500);
DISPLAY INVISIBLE (1450 6500);
FORCEPROP 1 LAST PACK_TYPE 0402LF
J 0
(1700 6450);
DISPLAY 0.510638 (1700 6450);
PAINT SKYBLUE (1700 6450);
DISPLAY INVISIBLE (1700 6450);
FORCEPROP 2 LAST CDS_LIB pure_quanta
J 0
(1450 6600);
DISPLAY INVISIBLE (1450 6600);
FORCEPROP 1 LAST PATH I100
J 0
(1400 6750);
DISPLAY 0.978723 (1400 6750);
PAINT WHITE (1400 6750);
DISPLAY INVISIBLE (1400 6750);
FORCEPROP 1 LAST PART_NUMBER CS02202FB02
J 0
(1400 6700);
DISPLAY 0.510638 (1400 6700);
PAINT WHITE (1400 6700);
DISPLAY INVISIBLE (1400 6700);
FORCEADD Q_RES..1
(1450 6450);
FORCEPROP 1 LAST LOCATION R73
J 0
(1150 6450);
DISPLAY 0.702128 (1150 6450);
PAINT YELLOW (1150 6450);
FORCEPROP 0 LAST $SEC 1
J 0
(1525 6500);
DISPLAY INVISIBLE (1525 6500);
FORCEPROP 0 LAST CDS_SEC 1
J 0
(1525 6500);
DISPLAY INVISIBLE (1525 6500);
FORCEPROP 1 LASTPIN (1350 6450) $PN 1
J 0
(1362 6462);
DISPLAY 0.808511 (1362 6462);
PAINT WHITE (1362 6462);
DISPLAY INVISIBLE (1362 6462);
FORCEPROP 1 LASTPIN (1550 6450) $PN 2
J 0
(1512 6462);
DISPLAY 0.808511 (1512 6462);
PAINT WHITE (1512 6462);
DISPLAY INVISIBLE (1512 6462);
FORCEPROP 1 LAST VALUE 22
J 2
(1400 6475);
DISPLAY 0.510638 (1400 6475);
PAINT SKYBLUE (1400 6475);
FORCEPROP 1 LAST MATERIAL CHIP
J 0
(1525 6475);
DISPLAY 0.510638 (1525 6475);
PAINT SKYBLUE (1525 6475);
FORCEPROP 1 LAST WATTAGE 1/16W
J 2
(1425 6300);
DISPLAY 0.510638 (1425 6300);
PAINT SKYBLUE (1425 6300);
DISPLAY INVISIBLE (1425 6300);
FORCEPROP 1 LAST TOLERANCE 1%
J 0
(1450 6350);
DISPLAY 0.510638 (1450 6350);
PAINT SKYBLUE (1450 6350);
DISPLAY INVISIBLE (1450 6350);
FORCEPROP 1 LAST PACK_TYPE 0402LF
J 0
(1700 6300);
DISPLAY 0.510638 (1700 6300);
PAINT SKYBLUE (1700 6300);
DISPLAY INVISIBLE (1700 6300);
FORCEPROP 2 LAST CDS_LIB pure_quanta
J 0
(1450 6450);
DISPLAY INVISIBLE (1450 6450);
FORCEPROP 1 LAST PATH I101
J 0
(1400 6600);
DISPLAY 0.978723 (1400 6600);
PAINT WHITE (1400 6600);
DISPLAY INVISIBLE (1400 6600);
FORCEPROP 1 LAST PART_NUMBER CS02202FB02
J 0
(1400 6550);
DISPLAY 0.510638 (1400 6550);
PAINT WHITE (1400 6550);
DISPLAY INVISIBLE (1400 6550);
FORCEADD Q_RES..1
(1450 5325);
FORCEPROP 1 LAST LOCATION R74
J 0
(1150 5325);
DISPLAY 0.702128 (1150 5325);
FORCEPROP 0 LAST $SEC 1
J 0
(1525 5375);
DISPLAY INVISIBLE (1525 5375);
FORCEPROP 0 LAST CDS_SEC 1
J 0
(1525 5375);
DISPLAY INVISIBLE (1525 5375);
FORCEPROP 1 LASTPIN (1350 5325) $PN 1
J 0
(1362 5337);
DISPLAY 0.808511 (1362 5337);
PAINT WHITE (1362 5337);
DISPLAY INVISIBLE (1362 5337);
FORCEPROP 1 LASTPIN (1550 5325) $PN 2
J 0
(1512 5337);
DISPLAY 0.808511 (1512 5337);
PAINT WHITE (1512 5337);
DISPLAY INVISIBLE (1512 5337);
FORCEPROP 1 LAST VALUE 0
J 2
(1600 5325);
DISPLAY 0.638298 (1600 5325);
FORCEPROP 1 LAST MATERIAL CHIP
J 0
(1650 5325);
DISPLAY 0.638298 (1650 5325);
FORCEPROP 1 LAST TOLERANCE 5%
J 0
(1450 5225);
DISPLAY 0.510638 (1450 5225);
PAINT SKYBLUE (1450 5225);
DISPLAY INVISIBLE (1450 5225);
FORCEPROP 2 LAST CDS_LIB pure_quanta
J 0
(1450 5325);
DISPLAY INVISIBLE (1450 5325);
FORCEPROP 1 LAST PACK_TYPE 0402LF
J 0
(1700 5175);
DISPLAY 0.510638 (1700 5175);
PAINT SKYBLUE (1700 5175);
DISPLAY INVISIBLE (1700 5175);
FORCEPROP 1 LAST WATTAGE 1/16W
J 2
(1425 5175);
DISPLAY 0.510638 (1425 5175);
PAINT SKYBLUE (1425 5175);
DISPLAY INVISIBLE (1425 5175);
FORCEPROP 1 LAST PATH I102
J 0
(1400 5475);
DISPLAY 0.978723 (1400 5475);
PAINT WHITE (1400 5475);
DISPLAY INVISIBLE (1400 5475);
FORCEPROP 1 LAST PART_NUMBER CS00002JB13
J 0
(1325 5400);
DISPLAY 0.510638 (1325 5400);
DISPLAY INVISIBLE (1325 5400);
FORCEADD Q_RES..1
(1450 5175);
FORCEPROP 1 LAST LOCATION R75
J 0
(1150 5175);
DISPLAY 0.702128 (1150 5175);
FORCEPROP 0 LAST $SEC 1
J 0
(1525 5225);
DISPLAY INVISIBLE (1525 5225);
FORCEPROP 0 LAST CDS_SEC 1
J 0
(1525 5225);
DISPLAY INVISIBLE (1525 5225);
FORCEPROP 1 LASTPIN (1350 5175) $PN 1
J 0
(1362 5187);
DISPLAY 0.808511 (1362 5187);
PAINT WHITE (1362 5187);
DISPLAY INVISIBLE (1362 5187);
FORCEPROP 1 LASTPIN (1550 5175) $PN 2
J 0
(1512 5187);
DISPLAY 0.808511 (1512 5187);
PAINT WHITE (1512 5187);
DISPLAY INVISIBLE (1512 5187);
FORCEPROP 1 LAST MATERIAL CHIP
J 0
(1650 5175);
DISPLAY 0.638298 (1650 5175);
FORCEPROP 1 LAST VALUE 0
J 2
(1600 5175);
DISPLAY 0.638298 (1600 5175);
FORCEPROP 1 LAST TOLERANCE 5%
J 0
(1450 5075);
DISPLAY 0.510638 (1450 5075);
PAINT SKYBLUE (1450 5075);
DISPLAY INVISIBLE (1450 5075);
FORCEPROP 1 LAST WATTAGE 1/16W
J 2
(1425 5025);
DISPLAY 0.510638 (1425 5025);
PAINT SKYBLUE (1425 5025);
DISPLAY INVISIBLE (1425 5025);
FORCEPROP 1 LAST PACK_TYPE 0402LF
J 0
(1700 5025);
DISPLAY 0.510638 (1700 5025);
PAINT SKYBLUE (1700 5025);
DISPLAY INVISIBLE (1700 5025);
FORCEPROP 2 LAST CDS_LIB pure_quanta
J 0
(1450 5175);
DISPLAY INVISIBLE (1450 5175);
FORCEPROP 1 LAST PATH I103
J 0
(1400 5325);
DISPLAY 0.978723 (1400 5325);
PAINT WHITE (1400 5325);
DISPLAY INVISIBLE (1400 5325);
FORCEPROP 1 LAST PART_NUMBER CS00002JB13
J 0
(1400 5275);
DISPLAY 0.510638 (1400 5275);
PAINT WHITE (1400 5275);
DISPLAY INVISIBLE (1400 5275);
FORCEADD Q_RES..1
(1450 5025);
FORCEPROP 1 LAST LOCATION R76
J 0
(1150 5025);
DISPLAY 0.702128 (1150 5025);
FORCEPROP 0 LAST $SEC 1
J 0
(1525 5075);
DISPLAY INVISIBLE (1525 5075);
FORCEPROP 0 LAST CDS_SEC 1
J 0
(1525 5075);
DISPLAY INVISIBLE (1525 5075);
FORCEPROP 1 LASTPIN (1350 5025) $PN 1
J 0
(1362 5037);
DISPLAY 0.808511 (1362 5037);
PAINT WHITE (1362 5037);
DISPLAY INVISIBLE (1362 5037);
FORCEPROP 1 LASTPIN (1550 5025) $PN 2
J 0
(1512 5037);
DISPLAY 0.808511 (1512 5037);
PAINT WHITE (1512 5037);
DISPLAY INVISIBLE (1512 5037);
FORCEPROP 1 LAST VALUE 0
J 2
(1600 5025);
DISPLAY 0.638298 (1600 5025);
FORCEPROP 1 LAST MATERIAL CHIP
J 0
(1650 5025);
DISPLAY 0.638298 (1650 5025);
FORCEPROP 1 LAST TOLERANCE 5%
J 0
(1450 4925);
DISPLAY 0.510638 (1450 4925);
PAINT SKYBLUE (1450 4925);
DISPLAY INVISIBLE (1450 4925);
FORCEPROP 1 LAST WATTAGE 1/16W
J 2
(1425 4875);
DISPLAY 0.510638 (1425 4875);
PAINT SKYBLUE (1425 4875);
DISPLAY INVISIBLE (1425 4875);
FORCEPROP 1 LAST PACK_TYPE 0402LF
J 0
(1700 4875);
DISPLAY 0.510638 (1700 4875);
PAINT SKYBLUE (1700 4875);
DISPLAY INVISIBLE (1700 4875);
FORCEPROP 2 LAST CDS_LIB pure_quanta
J 0
(1450 5025);
DISPLAY INVISIBLE (1450 5025);
FORCEPROP 1 LAST PATH I104
J 0
(1400 5175);
DISPLAY 0.978723 (1400 5175);
PAINT WHITE (1400 5175);
DISPLAY INVISIBLE (1400 5175);
FORCEPROP 1 LAST PART_NUMBER CS00002JB13
J 0
(1400 5125);
DISPLAY 0.510638 (1400 5125);
PAINT WHITE (1400 5125);
DISPLAY INVISIBLE (1400 5125);
FORCEADD OFFPAGE..2
(3150 2800);
FORCEPROP 2 LAST $XR0 131 
J 0
(3339 2800);
DISPLAY 0.638298 (3339 2800);
PAINT MONO (3339 2800);
FORCEPROP 2 LAST CDS_LIB standard
J 0
(3150 2800);
PAINT MONO (3150 2800);
DISPLAY INVISIBLE (3150 2800);
FORCEPROP 1 LAST OFFPAGE TRUE
J 0
(3475 2675);
DISPLAY 0.872340 (3475 2675);
PAINT GREEN (3475 2675);
DISPLAY INVISIBLE (3475 2675);
FORCEPROP 1 LAST COMMENT_BODY TRUE
J 0
(3105 2705);
DISPLAY 0.872340 (3105 2705);
PAINT GREEN (3105 2705);
DISPLAY INVISIBLE (3105 2705);
FORCEPROP 2 LAST PATH I110
J 0
(3500 2850);
DISPLAY 1.021277 (3500 2850);
DISPLAY INVISIBLE (3500 2850);
FORCEADD OFFPAGE..2
(3150 2650);
FORCEPROP 2 LAST $XR0 131 
J 0
(3339 2650);
DISPLAY 0.638298 (3339 2650);
PAINT MONO (3339 2650);
FORCEPROP 2 LAST CDS_LIB standard
J 0
(3150 2650);
PAINT MONO (3150 2650);
DISPLAY INVISIBLE (3150 2650);
FORCEPROP 1 LAST OFFPAGE TRUE
J 0
(3475 2525);
DISPLAY 0.872340 (3475 2525);
PAINT GREEN (3475 2525);
DISPLAY INVISIBLE (3475 2525);
FORCEPROP 1 LAST COMMENT_BODY TRUE
J 0
(3105 2555);
DISPLAY 0.872340 (3105 2555);
PAINT GREEN (3105 2555);
DISPLAY INVISIBLE (3105 2555);
FORCEPROP 2 LAST PATH I111
J 0
(3500 2700);
DISPLAY 1.021277 (3500 2700);
DISPLAY INVISIBLE (3500 2700);
FORCEADD OFFPAGE..2
(3150 2500);
FORCEPROP 2 LAST $XR0 131 
J 0
(3339 2500);
DISPLAY 0.638298 (3339 2500);
PAINT MONO (3339 2500);
FORCEPROP 2 LAST CDS_LIB standard
J 0
(3150 2500);
PAINT MONO (3150 2500);
DISPLAY INVISIBLE (3150 2500);
FORCEPROP 1 LAST OFFPAGE TRUE
J 0
(3475 2375);
DISPLAY 0.872340 (3475 2375);
PAINT GREEN (3475 2375);
DISPLAY INVISIBLE (3475 2375);
FORCEPROP 1 LAST COMMENT_BODY TRUE
J 0
(3105 2405);
DISPLAY 0.872340 (3105 2405);
PAINT GREEN (3105 2405);
DISPLAY INVISIBLE (3105 2405);
FORCEPROP 2 LAST PATH I112
J 0
(3500 2550);
DISPLAY 1.021277 (3500 2550);
DISPLAY INVISIBLE (3500 2550);
FORCEADD Q_RES..1
(-3450 3950);
FORCEPROP 1 LAST LOCATION R1719
J 0
(-3700 3950);
DISPLAY 0.638298 (-3700 3950);
FORCEPROP 2 LAST $SEC 1
J 0
(-3500 4150);
DISPLAY 0.680851 (-3500 4150);
PAINT MONO (-3500 4150);
DISPLAY INVISIBLE (-3500 4150);
FORCEPROP 2 LAST CDS_SEC 1
J 0
(-3500 4150);
DISPLAY 1.021277 (-3500 4150);
DISPLAY INVISIBLE (-3500 4150);
FORCEPROP 1 LASTPIN (-3550 3950) $PN 1
J 0
(-3538 3962);
DISPLAY 0.787234 (-3538 3962);
FORCEPROP 1 LASTPIN (-3350 3950) $PN 2
J 0
(-3388 3962);
DISPLAY 0.787234 (-3388 3962);
FORCEPROP 1 LAST MATERIAL CHIP
J 0
(-3550 4075);
DISPLAY 0.510638 (-3550 4075);
FORCEPROP 1 LAST WATTAGE 1/16W
J 2
(-3275 4075);
DISPLAY 0.510638 (-3275 4075);
FORCEPROP 1 LAST PACK_TYPE 0402LF
J 0
(-3550 4125);
DISPLAY 0.510638 (-3550 4125);
FORCEPROP 1 LAST VALUE 33.2
J 2
(-3250 3950);
DISPLAY 0.510638 (-3250 3950);
FORCEPROP 1 LAST TOLERANCE 1%
J 0
(-3225 3950);
DISPLAY 0.510638 (-3225 3950);
FORCEPROP 2 LAST CDS_LIB pure_quanta
J 0
(-3450 3950);
PAINT MONO (-3450 3950);
DISPLAY INVISIBLE (-3450 3950);
FORCEPROP 1 LAST PATH I119
J 0
(-3500 4100);
DISPLAY 0.978723 (-3500 4100);
PAINT WHITE (-3500 4100);
DISPLAY INVISIBLE (-3500 4100);
FORCEPROP 1 LAST PART_NUMBER CS03322FB03
J 0
(-3550 4025);
DISPLAY 0.510638 (-3550 4025);
DISPLAY INVISIBLE (-3550 4025);
FORCEADD OFFPAGE..1
(-4500 3950);
FORCEPROP 2 LAST $XR2 132 
J 0
(-4992 3950);
DISPLAY 0.638298 (-4992 3950);
PAINT MONO (-4992 3950);
FORCEPROP 2 LAST $XR1 136 
J 0
(-4872 3950);
DISPLAY 0.638298 (-4872 3950);
PAINT MONO (-4872 3950);
FORCEPROP 2 LAST $XR0 131 
J 0
(-4752 3950);
DISPLAY 0.638298 (-4752 3950);
PAINT MONO (-4752 3950);
FORCEPROP 2 LAST CDS_LIB standard
J 0
(-4500 3950);
PAINT MONO (-4500 3950);
DISPLAY INVISIBLE (-4500 3950);
FORCEPROP 1 LAST OFFPAGE TRUE
J 0
(-4175 3825);
DISPLAY 0.872340 (-4175 3825);
PAINT GREEN (-4175 3825);
DISPLAY INVISIBLE (-4175 3825);
FORCEPROP 1 LAST COMMENT_BODY TRUE
J 0
(-4375 3850);
DISPLAY 0.872340 (-4375 3850);
PAINT GREEN (-4375 3850);
DISPLAY INVISIBLE (-4375 3850);
FORCEPROP 2 LAST PATH I120
J 0
(-4775 4000);
DISPLAY 1.021277 (-4775 4000);
DISPLAY INVISIBLE (-4775 4000);
FORCEADD Q_RES..2
(2375 2100);
FORCEPROP 1 LAST LOCATION R1898
J 0
(2420 2225);
DISPLAY 0.638298 (2420 2225);
FORCEPROP 0 LAST $SEC 1
J 0
(2425 2275);
DISPLAY 0.680851 (2425 2275);
PAINT MONO (2425 2275);
DISPLAY INVISIBLE (2425 2275);
FORCEPROP 0 LAST CDS_SEC 1
J 0
(2425 2275);
DISPLAY 1.021277 (2425 2275);
DISPLAY INVISIBLE (2425 2275);
FORCEPROP 1 LASTPIN (2375 2200) $PN 1
J 0
(2380 2162);
DISPLAY 0.787234 (2380 2162);
PAINT MONO (2380 2162);
FORCEPROP 1 LASTPIN (2375 2000) $PN 2
J 0
(2380 2010);
DISPLAY 0.787234 (2380 2010);
PAINT MONO (2380 2010);
FORCEPROP 1 LAST PACK_TYPE 0402LF
J 0
(2415 1925);
DISPLAY 0.638298 (2415 1925);
FORCEPROP 1 LAST MATERIAL CHIP
J 0
(2415 2025);
DISPLAY 0.638298 (2415 2025);
FORCEPROP 1 LAST WATTAGE 1/16W
J 0
(2415 2075);
DISPLAY 0.638298 (2415 2075);
FORCEPROP 1 LAST VALUE 100
J 0
(2420 2175);
DISPLAY 0.638298 (2420 2175);
FORCEPROP 1 LAST TOLERANCE 1%
J 0
(2420 2125);
DISPLAY 0.638298 (2420 2125);
FORCEPROP 2 LAST CDS_LIB pure_quanta
J 0
(2375 2100);
DISPLAY INVISIBLE (2375 2100);
FORCEPROP 1 LAST PATH I122
J 0
(2425 2275);
DISPLAY 0.978723 (2425 2275);
PAINT WHITE (2425 2275);
DISPLAY INVISIBLE (2425 2275);
FORCEPROP 1 LAST PART_NUMBER CS11002FB07
J 0
(2415 1975);
DISPLAY 0.638298 (2415 1975);
DISPLAY INVISIBLE (2415 1975);
FORCEADD Q_RES..2
(1875 2100);
FORCEPROP 1 LAST LOCATION R1896
J 0
(1920 2225);
DISPLAY 0.638298 (1920 2225);
FORCEPROP 0 LAST $SEC 1
J 0
(1925 2275);
DISPLAY 0.680851 (1925 2275);
PAINT MONO (1925 2275);
DISPLAY INVISIBLE (1925 2275);
FORCEPROP 0 LAST CDS_SEC 1
J 0
(1925 2275);
DISPLAY 1.021277 (1925 2275);
DISPLAY INVISIBLE (1925 2275);
FORCEPROP 1 LASTPIN (1875 2200) $PN 1
J 0
(1880 2162);
DISPLAY 0.787234 (1880 2162);
PAINT MONO (1880 2162);
FORCEPROP 1 LASTPIN (1875 2000) $PN 2
J 0
(1880 2010);
DISPLAY 0.787234 (1880 2010);
PAINT MONO (1880 2010);
FORCEPROP 1 LAST VALUE 100
J 0
(1920 2175);
DISPLAY 0.638298 (1920 2175);
FORCEPROP 1 LAST PACK_TYPE 0402LF
J 0
(1925 1975);
DISPLAY 0.638298 (1925 1975);
FORCEPROP 1 LAST WATTAGE 1/16W
J 0
(1915 2075);
DISPLAY 0.638298 (1915 2075);
FORCEPROP 1 LAST MATERIAL CHIP
J 0
(1915 2025);
DISPLAY 0.638298 (1915 2025);
FORCEPROP 1 LAST TOLERANCE 1%
J 0
(1920 2125);
DISPLAY 0.638298 (1920 2125);
FORCEPROP 2 LAST CDS_LIB pure_quanta
J 0
(1875 2100);
DISPLAY INVISIBLE (1875 2100);
FORCEPROP 1 LAST PATH I123
J 0
(1925 2275);
DISPLAY 0.978723 (1925 2275);
PAINT WHITE (1925 2275);
DISPLAY INVISIBLE (1925 2275);
FORCEPROP 1 LAST PART_NUMBER CS11002FB07
J 0
(1915 1975);
DISPLAY 0.638298 (1915 1975);
DISPLAY INVISIBLE (1915 1975);
FORCEADD Q_RES..2
(2125 2100);
FORCEPROP 1 LAST LOCATION R1897
J 0
(2170 2225);
DISPLAY 0.638298 (2170 2225);
FORCEPROP 0 LAST $SEC 1
J 0
(2175 2275);
DISPLAY 0.680851 (2175 2275);
PAINT MONO (2175 2275);
DISPLAY INVISIBLE (2175 2275);
FORCEPROP 0 LAST CDS_SEC 1
J 0
(2175 2275);
DISPLAY 1.021277 (2175 2275);
DISPLAY INVISIBLE (2175 2275);
FORCEPROP 1 LASTPIN (2125 2200) $PN 1
J 0
(2130 2162);
DISPLAY 0.787234 (2130 2162);
PAINT MONO (2130 2162);
FORCEPROP 1 LASTPIN (2125 2000) $PN 2
J 0
(2130 2010);
DISPLAY 0.787234 (2130 2010);
PAINT MONO (2130 2010);
FORCEPROP 1 LAST WATTAGE 1/16W
J 0
(2165 2075);
DISPLAY 0.638298 (2165 2075);
FORCEPROP 1 LAST TOLERANCE 1%
J 0
(2170 2125);
DISPLAY 0.638298 (2170 2125);
FORCEPROP 1 LAST VALUE 100
J 0
(2170 2175);
DISPLAY 0.638298 (2170 2175);
FORCEPROP 1 LAST MATERIAL CHIP
J 0
(2165 2025);
DISPLAY 0.638298 (2165 2025);
FORCEPROP 1 LAST PACK_TYPE 0402LF
J 0
(2175 1975);
DISPLAY 0.638298 (2175 1975);
FORCEPROP 2 LAST CDS_LIB pure_quanta
J 0
(2125 2100);
DISPLAY INVISIBLE (2125 2100);
FORCEPROP 1 LAST PATH I124
J 0
(2175 2275);
DISPLAY 0.978723 (2175 2275);
PAINT WHITE (2175 2275);
DISPLAY INVISIBLE (2175 2275);
FORCEPROP 1 LAST PART_NUMBER CS11002FB07
J 0
(2165 1975);
DISPLAY 0.638298 (2165 1975);
DISPLAY INVISIBLE (2165 1975);
FORCEADD UNIVERSAL_GND..1
(2375 1825);
FORCEPROP 3 LASTPIN (2375 1875) SIG_NAME GND\g
J 0
(2385 1885);
DISPLAY 0.659574 (2385 1885);
PAINT MONO (2385 1885);
DISPLAY INVISIBLE (2385 1885);
FORCEPROP 2 LAST CDS_LIB pure_quanta_power
J 0
(2375 1825);
DISPLAY INVISIBLE (2375 1825);
FORCEPROP 1 LAST HDL_POWER GND
J 1
(2400 1750);
DISPLAY 0.872340 (2400 1750);
PAINT GREEN (2400 1750);
DISPLAY INVISIBLE (2400 1750);
FORCEPROP 1 LAST PATH I125
J 0
(2450 1825);
DISPLAY 0.872340 (2450 1825);
PAINT AQUA (2450 1825);
DISPLAY INVISIBLE (2450 1825);
FORCEADD OFFPAGE..1
(-1800 3475);
FORCEPROP 2 LAST $XR0 81 
J 0
(-2021 3475);
DISPLAY 0.638298 (-2021 3475);
PAINT MONO (-2021 3475);
FORCEPROP 2 LAST CDS_LIB standard
J 0
(-1800 3475);
DISPLAY INVISIBLE (-1800 3475);
FORCEPROP 1 LAST OFFPAGE TRUE
J 0
(-1475 3350);
DISPLAY 0.872340 (-1475 3350);
PAINT GREEN (-1475 3350);
DISPLAY INVISIBLE (-1475 3350);
FORCEPROP 1 LAST COMMENT_BODY TRUE
J 0
(-1675 3375);
DISPLAY 0.872340 (-1675 3375);
PAINT GREEN (-1675 3375);
DISPLAY INVISIBLE (-1675 3375);
FORCEPROP 2 LAST PATH I128
J 0
(-2075 3525);
DISPLAY 1.021277 (-2075 3525);
DISPLAY INVISIBLE (-2075 3525);
FORCEADD Q_RES..1
(3025 3725);
FORCEPROP 1 LAST LOCATION R84
J 0
(2800 3725);
DISPLAY 0.638298 (2800 3725);
FORCEPROP 2 LAST $SEC 1
J 0
(2975 3925);
DISPLAY 0.680851 (2975 3925);
PAINT MONO (2975 3925);
DISPLAY INVISIBLE (2975 3925);
FORCEPROP 2 LAST CDS_SEC 1
J 0
(2975 3925);
DISPLAY 1.021277 (2975 3925);
DISPLAY INVISIBLE (2975 3925);
FORCEPROP 1 LASTPIN (2925 3725) $PN 1
J 0
(2937 3737);
DISPLAY 0.787234 (2937 3737);
FORCEPROP 1 LASTPIN (3125 3725) $PN 2
J 0
(3087 3737);
DISPLAY 0.787234 (3087 3737);
FORCEPROP 1 LAST MATERIAL CHIP
J 0
(3375 3725);
DISPLAY 0.638298 (3375 3725);
FORCEPROP 1 LAST VALUE 100K
J 2
(3250 3725);
DISPLAY 0.638298 (3250 3725);
FORCEPROP 1 LAST TOLERANCE 1%
J 0
(3275 3725);
DISPLAY 0.638298 (3275 3725);
FORCEPROP 1 LAST PACK_TYPE 0402LF
J 0
(2850 3875);
DISPLAY 0.638298 (2850 3875);
DISPLAY INVISIBLE (2850 3875);
FORCEPROP 1 LAST WATTAGE 1/16W
J 2
(3300 3875);
DISPLAY 0.638298 (3300 3875);
DISPLAY INVISIBLE (3300 3875);
FORCEPROP 2 LAST CDS_LIB pure_quanta
J 0
(3025 3725);
PAINT MONO (3025 3725);
DISPLAY INVISIBLE (3025 3725);
FORCEPROP 1 LAST PATH I129
J 0
(2975 3875);
DISPLAY 0.978723 (2975 3875);
PAINT WHITE (2975 3875);
DISPLAY INVISIBLE (2975 3875);
FORCEPROP 1 LAST PART_NUMBER CS41002FB09
J 0
(2850 3825);
DISPLAY 0.638298 (2850 3825);
DISPLAY INVISIBLE (2850 3825);
FORCEADD UNIVERSAL_GND..1
(3625 3325);
FORCEPROP 3 LASTPIN (3625 3375) SIG_NAME GND\g
J 0
(3635 3385);
DISPLAY 0.659574 (3635 3385);
PAINT MONO (3635 3385);
DISPLAY INVISIBLE (3635 3385);
FORCEPROP 2 LAST CDS_LIB pure_quanta_power
J 0
(3625 3325);
PAINT MONO (3625 3325);
DISPLAY INVISIBLE (3625 3325);
FORCEPROP 1 LAST HDL_POWER GND
J 1
(3650 3250);
DISPLAY 0.872340 (3650 3250);
PAINT GREEN (3650 3250);
DISPLAY INVISIBLE (3650 3250);
FORCEPROP 1 LAST PATH I130
J 0
(3700 3325);
DISPLAY 0.872340 (3700 3325);
PAINT AQUA (3700 3325);
DISPLAY INVISIBLE (3700 3325);
FORCEADD Q_RES..1
(3025 4475);
FORCEPROP 1 LAST LOCATION R77
J 0
(2800 4475);
DISPLAY 0.638298 (2800 4475);
FORCEPROP 2 LAST $SEC 1
J 0
(2975 4675);
DISPLAY 0.680851 (2975 4675);
PAINT MONO (2975 4675);
DISPLAY INVISIBLE (2975 4675);
FORCEPROP 2 LAST CDS_SEC 1
J 0
(2975 4675);
DISPLAY 1.021277 (2975 4675);
DISPLAY INVISIBLE (2975 4675);
FORCEPROP 1 LASTPIN (2925 4475) $PN 1
J 0
(2937 4487);
DISPLAY 0.787234 (2937 4487);
FORCEPROP 1 LASTPIN (3125 4475) $PN 2
J 0
(3087 4487);
DISPLAY 0.787234 (3087 4487);
FORCEPROP 1 LAST VALUE 100K
J 2
(3250 4475);
DISPLAY 0.638298 (3250 4475);
FORCEPROP 1 LAST WATTAGE 1/16W
J 2
(3325 4600);
DISPLAY 0.510638 (3325 4600);
FORCEPROP 1 LAST MATERIAL CHIP
J 0
(3375 4475);
DISPLAY 0.638298 (3375 4475);
FORCEPROP 1 LAST TOLERANCE 1%
J 0
(3275 4475);
DISPLAY 0.638298 (3275 4475);
FORCEPROP 1 LAST PACK_TYPE 0402LF
J 0
(2875 4600);
DISPLAY 0.510638 (2875 4600);
FORCEPROP 2 LAST CDS_LIB pure_quanta
J 0
(3025 4475);
PAINT MONO (3025 4475);
DISPLAY INVISIBLE (3025 4475);
FORCEPROP 1 LAST PATH I131
J 0
(2975 4625);
DISPLAY 0.978723 (2975 4625);
PAINT WHITE (2975 4625);
DISPLAY INVISIBLE (2975 4625);
FORCEPROP 1 LAST PART_NUMBER CS41002FB09
J 0
(2875 4550);
DISPLAY 0.510638 (2875 4550);
DISPLAY INVISIBLE (2875 4550);
FORCEADD Q_RES..1
(3025 4325);
FORCEPROP 1 LAST LOCATION R79
J 0
(2800 4325);
DISPLAY 0.638298 (2800 4325);
FORCEPROP 2 LAST $SEC 1
J 0
(2975 4525);
DISPLAY 0.680851 (2975 4525);
PAINT MONO (2975 4525);
DISPLAY INVISIBLE (2975 4525);
FORCEPROP 2 LAST CDS_SEC 1
J 0
(2975 4525);
DISPLAY 1.021277 (2975 4525);
DISPLAY INVISIBLE (2975 4525);
FORCEPROP 1 LASTPIN (2925 4325) $PN 1
J 0
(2937 4337);
DISPLAY 0.787234 (2937 4337);
FORCEPROP 1 LASTPIN (3125 4325) $PN 2
J 0
(3087 4337);
DISPLAY 0.787234 (3087 4337);
FORCEPROP 1 LAST TOLERANCE 1%
J 0
(3275 4325);
DISPLAY 0.638298 (3275 4325);
FORCEPROP 1 LAST MATERIAL CHIP
J 0
(3375 4325);
DISPLAY 0.638298 (3375 4325);
FORCEPROP 1 LAST VALUE 100K
J 2
(3250 4325);
DISPLAY 0.638298 (3250 4325);
FORCEPROP 1 LAST PACK_TYPE 0402LF
J 0
(2850 4475);
DISPLAY 0.638298 (2850 4475);
DISPLAY INVISIBLE (2850 4475);
FORCEPROP 1 LAST WATTAGE 1/16W
J 2
(3300 4475);
DISPLAY 0.638298 (3300 4475);
DISPLAY INVISIBLE (3300 4475);
FORCEPROP 2 LAST CDS_LIB pure_quanta
J 0
(3025 4325);
PAINT MONO (3025 4325);
DISPLAY INVISIBLE (3025 4325);
FORCEPROP 1 LAST PATH I132
J 0
(2975 4475);
DISPLAY 0.978723 (2975 4475);
PAINT WHITE (2975 4475);
DISPLAY INVISIBLE (2975 4475);
FORCEPROP 1 LAST PART_NUMBER CS41002FB09
J 0
(2850 4425);
DISPLAY 0.638298 (2850 4425);
DISPLAY INVISIBLE (2850 4425);
FORCEADD Q_RES..1
(3025 4175);
FORCEPROP 1 LAST LOCATION R80
J 0
(2800 4175);
DISPLAY 0.638298 (2800 4175);
FORCEPROP 2 LAST $SEC 1
J 0
(2975 4375);
DISPLAY 0.680851 (2975 4375);
PAINT MONO (2975 4375);
DISPLAY INVISIBLE (2975 4375);
FORCEPROP 2 LAST CDS_SEC 1
J 0
(2975 4375);
DISPLAY 1.021277 (2975 4375);
DISPLAY INVISIBLE (2975 4375);
FORCEPROP 1 LASTPIN (2925 4175) $PN 1
J 0
(2937 4187);
DISPLAY 0.787234 (2937 4187);
FORCEPROP 1 LASTPIN (3125 4175) $PN 2
J 0
(3087 4187);
DISPLAY 0.787234 (3087 4187);
FORCEPROP 1 LAST VALUE 100K
J 2
(3250 4175);
DISPLAY 0.638298 (3250 4175);
FORCEPROP 1 LAST MATERIAL CHIP
J 0
(3375 4175);
DISPLAY 0.638298 (3375 4175);
FORCEPROP 1 LAST TOLERANCE 1%
J 0
(3275 4175);
DISPLAY 0.638298 (3275 4175);
FORCEPROP 1 LAST PACK_TYPE 0402LF
J 0
(2850 4325);
DISPLAY 0.638298 (2850 4325);
DISPLAY INVISIBLE (2850 4325);
FORCEPROP 1 LAST WATTAGE 1/16W
J 2
(3300 4325);
DISPLAY 0.638298 (3300 4325);
DISPLAY INVISIBLE (3300 4325);
FORCEPROP 2 LAST CDS_LIB pure_quanta
J 0
(3025 4175);
PAINT MONO (3025 4175);
DISPLAY INVISIBLE (3025 4175);
FORCEPROP 1 LAST PATH I133
J 0
(2975 4325);
DISPLAY 0.978723 (2975 4325);
PAINT WHITE (2975 4325);
DISPLAY INVISIBLE (2975 4325);
FORCEPROP 1 LAST PART_NUMBER CS41002FB09
J 0
(2850 4275);
DISPLAY 0.638298 (2850 4275);
DISPLAY INVISIBLE (2850 4275);
FORCEADD Q_RES..1
(3025 4025);
FORCEPROP 1 LAST LOCATION R82
J 0
(2800 4025);
DISPLAY 0.638298 (2800 4025);
FORCEPROP 2 LAST $SEC 1
J 0
(2975 4225);
DISPLAY 0.680851 (2975 4225);
PAINT MONO (2975 4225);
DISPLAY INVISIBLE (2975 4225);
FORCEPROP 2 LAST CDS_SEC 1
J 0
(2975 4225);
DISPLAY 1.021277 (2975 4225);
DISPLAY INVISIBLE (2975 4225);
FORCEPROP 1 LASTPIN (2925 4025) $PN 1
J 0
(2937 4037);
DISPLAY 0.787234 (2937 4037);
FORCEPROP 1 LASTPIN (3125 4025) $PN 2
J 0
(3087 4037);
DISPLAY 0.787234 (3087 4037);
FORCEPROP 1 LAST MATERIAL CHIP
J 0
(3375 4025);
DISPLAY 0.638298 (3375 4025);
FORCEPROP 1 LAST TOLERANCE 1%
J 0
(3275 4025);
DISPLAY 0.638298 (3275 4025);
FORCEPROP 1 LAST VALUE 100K
J 2
(3250 4025);
DISPLAY 0.638298 (3250 4025);
FORCEPROP 2 LAST CDS_LIB pure_quanta
J 0
(3025 4025);
PAINT MONO (3025 4025);
DISPLAY INVISIBLE (3025 4025);
FORCEPROP 1 LAST WATTAGE 1/16W
J 2
(3300 4175);
DISPLAY 0.638298 (3300 4175);
DISPLAY INVISIBLE (3300 4175);
FORCEPROP 1 LAST PACK_TYPE 0402LF
J 0
(2850 4175);
DISPLAY 0.638298 (2850 4175);
DISPLAY INVISIBLE (2850 4175);
FORCEPROP 1 LAST PATH I134
J 0
(2975 4175);
DISPLAY 0.978723 (2975 4175);
PAINT WHITE (2975 4175);
DISPLAY INVISIBLE (2975 4175);
FORCEPROP 1 LAST PART_NUMBER CS41002FB09
J 0
(2850 4125);
DISPLAY 0.638298 (2850 4125);
DISPLAY INVISIBLE (2850 4125);
FORCEADD Q_RES..1
(3025 3875);
FORCEPROP 1 LAST LOCATION R83
J 0
(2800 3875);
DISPLAY 0.638298 (2800 3875);
FORCEPROP 2 LAST $SEC 1
J 0
(2975 4075);
DISPLAY 0.680851 (2975 4075);
PAINT MONO (2975 4075);
DISPLAY INVISIBLE (2975 4075);
FORCEPROP 2 LAST CDS_SEC 1
J 0
(2975 4075);
DISPLAY 1.021277 (2975 4075);
DISPLAY INVISIBLE (2975 4075);
FORCEPROP 1 LASTPIN (2925 3875) $PN 1
J 0
(2937 3887);
DISPLAY 0.787234 (2937 3887);
FORCEPROP 1 LASTPIN (3125 3875) $PN 2
J 0
(3087 3887);
DISPLAY 0.787234 (3087 3887);
FORCEPROP 1 LAST MATERIAL CHIP
J 0
(3375 3875);
DISPLAY 0.638298 (3375 3875);
FORCEPROP 1 LAST TOLERANCE 1%
J 0
(3275 3875);
DISPLAY 0.638298 (3275 3875);
FORCEPROP 1 LAST VALUE 100K
J 2
(3250 3875);
DISPLAY 0.638298 (3250 3875);
FORCEPROP 1 LAST PACK_TYPE 0402LF
J 0
(2850 4025);
DISPLAY 0.638298 (2850 4025);
DISPLAY INVISIBLE (2850 4025);
FORCEPROP 1 LAST WATTAGE 1/16W
J 2
(3300 4025);
DISPLAY 0.638298 (3300 4025);
DISPLAY INVISIBLE (3300 4025);
FORCEPROP 2 LAST CDS_LIB pure_quanta
J 0
(3025 3875);
PAINT MONO (3025 3875);
DISPLAY INVISIBLE (3025 3875);
FORCEPROP 1 LAST PATH I135
J 0
(2975 4025);
DISPLAY 0.978723 (2975 4025);
PAINT WHITE (2975 4025);
DISPLAY INVISIBLE (2975 4025);
FORCEPROP 1 LAST PART_NUMBER CS41002FB09
J 0
(2850 3975);
DISPLAY 0.638298 (2850 3975);
DISPLAY INVISIBLE (2850 3975);
FORCEADD Q_RES..1
(3025 3550);
FORCEPROP 1 LAST LOCATION R87
J 0
(2800 3550);
DISPLAY 0.510638 (2800 3550);
FORCEPROP 2 LAST $SEC 1
J 0
(2975 3750);
DISPLAY 0.680851 (2975 3750);
PAINT MONO (2975 3750);
DISPLAY INVISIBLE (2975 3750);
FORCEPROP 2 LAST CDS_SEC 1
J 0
(2975 3750);
DISPLAY 1.021277 (2975 3750);
DISPLAY INVISIBLE (2975 3750);
FORCEPROP 1 LASTPIN (2925 3550) $PN 1
J 0
(2937 3562);
DISPLAY 0.787234 (2937 3562);
FORCEPROP 1 LASTPIN (3125 3550) $PN 2
J 0
(3087 3562);
DISPLAY 0.787234 (3087 3562);
FORCEPROP 1 LAST PACK_TYPE 0402LF
J 0
(2875 3650);
DISPLAY 0.510638 (2875 3650);
FORCEPROP 1 LAST TOLERANCE 1%
J 0
(3275 3550);
DISPLAY 0.638298 (3275 3550);
FORCEPROP 1 LAST WATTAGE 1/16W
J 2
(3225 3650);
DISPLAY 0.638298 (3225 3650);
FORCEPROP 1 LAST VALUE 1K
J 2
(3225 3550);
DISPLAY 0.638298 (3225 3550);
FORCEPROP 1 LAST MATERIAL CHIP
J 0
(3375 3550);
DISPLAY 0.638298 (3375 3550);
FORCEPROP 2 LAST CDS_LIB pure_quanta
J 0
(3025 3550);
PAINT MONO (3025 3550);
DISPLAY INVISIBLE (3025 3550);
FORCEPROP 1 LAST PATH I136
J 0
(2975 3700);
DISPLAY 0.978723 (2975 3700);
PAINT WHITE (2975 3700);
DISPLAY INVISIBLE (2975 3700);
FORCEPROP 1 LAST PART_NUMBER CS21002FB06
J 0
(2875 3600);
DISPLAY 0.510638 (2875 3600);
DISPLAY INVISIBLE (2875 3600);
FORCEADD OFFPAGE..5
(1700 4475);
FORCEPROP 2 LAST $XR2 150 
J 0
(1205 4475);
DISPLAY 0.638298 (1205 4475);
PAINT MONO (1205 4475);
FORCEPROP 2 LAST $XR1 138 
J 0
(1325 4475);
DISPLAY 0.638298 (1325 4475);
PAINT MONO (1325 4475);
FORCEPROP 2 LAST $XR0 132 
J 0
(1445 4475);
DISPLAY 0.638298 (1445 4475);
PAINT MONO (1445 4475);
FORCEPROP 2 LAST CDS_LIB standard
J 0
(1700 4475);
PAINT MONO (1700 4475);
DISPLAY INVISIBLE (1700 4475);
FORCEPROP 1 LAST OFFPAGE TRUE
J 0
(2025 4350);
DISPLAY 0.872340 (2025 4350);
PAINT GREEN (2025 4350);
DISPLAY INVISIBLE (2025 4350);
FORCEPROP 1 LAST COMMENT_BODY TRUE
J 0
(1800 4400);
DISPLAY 0.872340 (1800 4400);
PAINT GREEN (1800 4400);
DISPLAY INVISIBLE (1800 4400);
FORCEPROP 2 LAST PATH I137
J 0
(1450 4525);
DISPLAY 1.021277 (1450 4525);
DISPLAY INVISIBLE (1450 4525);
FORCEADD OFFPAGE..5
(1700 4325);
FORCEPROP 2 LAST $XR2 150 
J 0
(1205 4325);
DISPLAY 0.638298 (1205 4325);
PAINT MONO (1205 4325);
FORCEPROP 2 LAST $XR1 138 
J 0
(1325 4325);
DISPLAY 0.638298 (1325 4325);
PAINT MONO (1325 4325);
FORCEPROP 2 LAST $XR0 132 
J 0
(1445 4325);
DISPLAY 0.638298 (1445 4325);
PAINT MONO (1445 4325);
FORCEPROP 2 LAST CDS_LIB standard
J 0
(1700 4325);
PAINT MONO (1700 4325);
DISPLAY INVISIBLE (1700 4325);
FORCEPROP 1 LAST OFFPAGE TRUE
J 0
(2025 4200);
DISPLAY 0.872340 (2025 4200);
PAINT GREEN (2025 4200);
DISPLAY INVISIBLE (2025 4200);
FORCEPROP 1 LAST COMMENT_BODY TRUE
J 0
(1800 4250);
DISPLAY 0.872340 (1800 4250);
PAINT GREEN (1800 4250);
DISPLAY INVISIBLE (1800 4250);
FORCEPROP 2 LAST PATH I138
J 0
(1450 4375);
DISPLAY 1.021277 (1450 4375);
DISPLAY INVISIBLE (1450 4375);
FORCEADD OFFPAGE..5
(1700 4175);
FORCEPROP 2 LAST $XR2 150 
J 0
(1205 4175);
DISPLAY 0.638298 (1205 4175);
PAINT MONO (1205 4175);
FORCEPROP 2 LAST $XR1 138 
J 0
(1325 4175);
DISPLAY 0.638298 (1325 4175);
PAINT MONO (1325 4175);
FORCEPROP 2 LAST $XR0 132 
J 0
(1445 4175);
DISPLAY 0.638298 (1445 4175);
PAINT MONO (1445 4175);
FORCEPROP 2 LAST CDS_LIB standard
J 0
(1700 4175);
PAINT MONO (1700 4175);
DISPLAY INVISIBLE (1700 4175);
FORCEPROP 1 LAST OFFPAGE TRUE
J 0
(2025 4050);
DISPLAY 0.872340 (2025 4050);
PAINT GREEN (2025 4050);
DISPLAY INVISIBLE (2025 4050);
FORCEPROP 1 LAST COMMENT_BODY TRUE
J 0
(1800 4100);
DISPLAY 0.872340 (1800 4100);
PAINT GREEN (1800 4100);
DISPLAY INVISIBLE (1800 4100);
FORCEPROP 2 LAST PATH I139
J 0
(1450 4225);
DISPLAY 1.021277 (1450 4225);
DISPLAY INVISIBLE (1450 4225);
FORCEADD OFFPAGE..5
(1700 4025);
FORCEPROP 2 LAST $XR2 138 
J 0
(1205 4025);
DISPLAY 0.638298 (1205 4025);
PAINT MONO (1205 4025);
FORCEPROP 2 LAST $XR1 132 
J 0
(1325 4025);
DISPLAY 0.638298 (1325 4025);
PAINT MONO (1325 4025);
FORCEPROP 2 LAST $XR0 150 
J 0
(1445 4025);
DISPLAY 0.638298 (1445 4025);
PAINT MONO (1445 4025);
FORCEPROP 2 LAST CDS_LIB standard
J 0
(1700 4025);
PAINT MONO (1700 4025);
DISPLAY INVISIBLE (1700 4025);
FORCEPROP 1 LAST OFFPAGE TRUE
J 0
(2025 3900);
DISPLAY 0.872340 (2025 3900);
PAINT GREEN (2025 3900);
DISPLAY INVISIBLE (2025 3900);
FORCEPROP 1 LAST COMMENT_BODY TRUE
J 0
(1800 3950);
DISPLAY 0.872340 (1800 3950);
PAINT GREEN (1800 3950);
DISPLAY INVISIBLE (1800 3950);
FORCEPROP 2 LAST PATH I140
J 0
(1450 4075);
DISPLAY 1.021277 (1450 4075);
DISPLAY INVISIBLE (1450 4075);
FORCEADD OFFPAGE..5
(1700 3725);
FORCEPROP 2 LAST $XR2 138 
J 0
(1205 3725);
DISPLAY 0.638298 (1205 3725);
PAINT MONO (1205 3725);
FORCEPROP 2 LAST $XR1 132 
J 0
(1325 3725);
DISPLAY 0.638298 (1325 3725);
PAINT MONO (1325 3725);
FORCEPROP 2 LAST $XR0 150 
J 0
(1445 3725);
DISPLAY 0.638298 (1445 3725);
PAINT MONO (1445 3725);
FORCEPROP 2 LAST CDS_LIB standard
J 0
(1700 3725);
PAINT MONO (1700 3725);
DISPLAY INVISIBLE (1700 3725);
FORCEPROP 1 LAST OFFPAGE TRUE
J 0
(2025 3600);
DISPLAY 0.872340 (2025 3600);
PAINT GREEN (2025 3600);
DISPLAY INVISIBLE (2025 3600);
FORCEPROP 1 LAST COMMENT_BODY TRUE
J 0
(1800 3650);
DISPLAY 0.872340 (1800 3650);
PAINT GREEN (1800 3650);
DISPLAY INVISIBLE (1800 3650);
FORCEPROP 2 LAST PATH I141
J 0
(1450 3775);
DISPLAY 1.021277 (1450 3775);
DISPLAY INVISIBLE (1450 3775);
FORCEADD OFFPAGE..5
(1700 3875);
FORCEPROP 2 LAST $XR2 138 
J 0
(1205 3875);
DISPLAY 0.638298 (1205 3875);
PAINT MONO (1205 3875);
FORCEPROP 2 LAST $XR1 132 
J 0
(1325 3875);
DISPLAY 0.638298 (1325 3875);
PAINT MONO (1325 3875);
FORCEPROP 2 LAST $XR0 150 
J 0
(1445 3875);
DISPLAY 0.638298 (1445 3875);
PAINT MONO (1445 3875);
FORCEPROP 2 LAST CDS_LIB standard
J 0
(1700 3875);
PAINT MONO (1700 3875);
DISPLAY INVISIBLE (1700 3875);
FORCEPROP 1 LAST OFFPAGE TRUE
J 0
(2025 3750);
DISPLAY 0.872340 (2025 3750);
PAINT GREEN (2025 3750);
DISPLAY INVISIBLE (2025 3750);
FORCEPROP 1 LAST COMMENT_BODY TRUE
J 0
(1800 3800);
DISPLAY 0.872340 (1800 3800);
PAINT GREEN (1800 3800);
DISPLAY INVISIBLE (1800 3800);
FORCEPROP 2 LAST PATH I142
J 0
(1450 3925);
DISPLAY 1.021277 (1450 3925);
DISPLAY INVISIBLE (1450 3925);
FORCEADD OFFPAGE..5
(1700 3550);
FORCEPROP 2 LAST $XR0 150 
J 0
(1445 3550);
DISPLAY 0.638298 (1445 3550);
PAINT MONO (1445 3550);
FORCEPROP 2 LAST CDS_LIB standard
J 0
(1700 3550);
PAINT MONO (1700 3550);
DISPLAY INVISIBLE (1700 3550);
FORCEPROP 1 LAST OFFPAGE TRUE
J 0
(2025 3425);
DISPLAY 0.872340 (2025 3425);
PAINT GREEN (2025 3425);
DISPLAY INVISIBLE (2025 3425);
FORCEPROP 1 LAST COMMENT_BODY TRUE
J 0
(1800 3475);
DISPLAY 0.872340 (1800 3475);
PAINT GREEN (1800 3475);
DISPLAY INVISIBLE (1800 3475);
FORCEPROP 2 LAST PATH I143
J 0
(1450 3600);
DISPLAY 1.021277 (1450 3600);
DISPLAY INVISIBLE (1450 3600);
FORCEADD OFFPAGE..1
(-3225 2325);
FORCEPROP 2 LAST $XR5 253 
J 0
(-4046 2325);
DISPLAY 0.638298 (-4046 2325);
PAINT MONO (-4046 2325);
FORCEPROP 2 LAST $XR4 251 
J 0
(-3926 2325);
DISPLAY 0.638298 (-3926 2325);
PAINT MONO (-3926 2325);
FORCEPROP 2 LAST $XR3 246 
J 0
(-3806 2325);
DISPLAY 0.638298 (-3806 2325);
PAINT MONO (-3806 2325);
FORCEPROP 2 LAST $XR2 241 
J 0
(-3686 2325);
DISPLAY 0.638298 (-3686 2325);
PAINT MONO (-3686 2325);
FORCEPROP 2 LAST $XR1 139 
J 0
(-3566 2325);
DISPLAY 0.638298 (-3566 2325);
PAINT MONO (-3566 2325);
FORCEPROP 2 LAST $XR0 80 
J 0
(-3446 2325);
DISPLAY 0.638298 (-3446 2325);
PAINT MONO (-3446 2325);
FORCEPROP 2 LAST CDS_LIB standard
J 0
(-3225 2325);
PAINT MONO (-3225 2325);
DISPLAY INVISIBLE (-3225 2325);
FORCEPROP 1 LAST OFFPAGE TRUE
J 0
(-2900 2200);
DISPLAY 0.872340 (-2900 2200);
PAINT GREEN (-2900 2200);
DISPLAY INVISIBLE (-2900 2200);
FORCEPROP 1 LAST COMMENT_BODY TRUE
J 0
(-3100 2225);
DISPLAY 0.872340 (-3100 2225);
PAINT GREEN (-3100 2225);
DISPLAY INVISIBLE (-3100 2225);
FORCEPROP 2 LAST PATH I145
J 0
(-3475 2375);
DISPLAY 1.021277 (-3475 2375);
DISPLAY INVISIBLE (-3475 2375);
FORCEADD UNIVERSAL_GND..1
(-2350 2475);
FORCEPROP 3 LASTPIN (-2350 2525) SIG_NAME GND\g
J 0
(-2340 2535);
DISPLAY 0.659574 (-2340 2535);
PAINT MONO (-2340 2535);
DISPLAY INVISIBLE (-2340 2535);
FORCEPROP 2 LAST CDS_LIB pure_quanta_power
J 0
(-2350 2475);
PAINT MONO (-2350 2475);
DISPLAY INVISIBLE (-2350 2475);
FORCEPROP 1 LAST HDL_POWER GND
J 1
(-2325 2400);
DISPLAY 0.872340 (-2325 2400);
PAINT GREEN (-2325 2400);
DISPLAY INVISIBLE (-2325 2400);
FORCEPROP 1 LAST PATH I146
J 0
(-2275 2475);
DISPLAY 0.872340 (-2275 2475);
PAINT AQUA (-2275 2475);
DISPLAY INVISIBLE (-2275 2475);
FORCEADD Q_CAP..1
R 2
(-2350 2700);
FORCEPROP 1 LAST LOCATION C1840
J 2
(-2400 2800);
DISPLAY 0.978723 (-2400 2800);
FORCEPROP 2 LAST $SEC 1
J 0
(-2400 2900);
DISPLAY 0.680851 (-2400 2900);
PAINT MONO (-2400 2900);
DISPLAY INVISIBLE (-2400 2900);
FORCEPROP 2 LAST CDS_SEC 1
J 0
(-2400 2900);
DISPLAY 1.021277 (-2400 2900);
DISPLAY INVISIBLE (-2400 2900);
FORCEPROP 1 LASTPIN (-2350 2800) $PN 1
J 2
(-2360 2780);
DISPLAY 0.787234 (-2360 2780);
FORCEPROP 1 LASTPIN (-2350 2600) $PN 2
J 2
(-2360 2580);
DISPLAY 0.787234 (-2360 2580);
FORCEPROP 1 LAST PACK_TYPE 0402
J 2
(-2400 2500);
DISPLAY 0.510638 (-2400 2500);
FORCEPROP 1 LAST VOLTAGE 25V
J 2
(-2400 2700);
DISPLAY 0.510638 (-2400 2700);
FORCEPROP 1 LAST VALUE 0.1UF
J 2
(-2400 2750);
DISPLAY 0.510638 (-2400 2750);
FORCEPROP 1 LAST MATERIAL X7R
J 2
(-2400 2600);
DISPLAY 0.510638 (-2400 2600);
FORCEPROP 1 LAST TOLERANCE 10%
J 2
(-2400 2650);
DISPLAY 0.510638 (-2400 2650);
FORCEPROP 2 LAST CDS_LIB pure_quanta
J 0
(-2350 2700);
PAINT MONO (-2350 2700);
DISPLAY INVISIBLE (-2350 2700);
FORCEPROP 1 LAST PATH I147
J 2
(-2400 2850);
DISPLAY 0.978723 (-2400 2850);
PAINT WHITE (-2400 2850);
DISPLAY INVISIBLE (-2400 2850);
FORCEPROP 1 LAST PART_NUMBER CH4104K1B00
J 2
(-2400 2550);
DISPLAY 0.510638 (-2400 2550);
DISPLAY INVISIBLE (-2400 2550);
FORCEADD UNIVERSAL_GND..1
(-975 5575);
FORCEPROP 3 LASTPIN (-975 5625) SIG_NAME GND\g
J 0
(-965 5635);
DISPLAY 0.659574 (-965 5635);
PAINT MONO (-965 5635);
DISPLAY INVISIBLE (-965 5635);
FORCEPROP 2 LAST CDS_LIB pure_quanta_power
J 0
(-975 5575);
PAINT MONO (-975 5575);
DISPLAY INVISIBLE (-975 5575);
FORCEPROP 1 LAST HDL_POWER GND
J 1
(-950 5500);
DISPLAY 0.872340 (-950 5500);
PAINT GREEN (-950 5500);
DISPLAY INVISIBLE (-950 5500);
FORCEPROP 1 LAST PATH I15
J 0
(-900 5575);
DISPLAY 0.872340 (-900 5575);
PAINT AQUA (-900 5575);
DISPLAY INVISIBLE (-900 5575);
FORCEADD UNIVERSAL_POWER..1
(-2350 3000);
FORCEPROP 3 LASTPIN (-2350 2950) SIG_NAME P3V3_AUX\g
J 0
(-2340 2960);
DISPLAY 0.659574 (-2340 2960);
PAINT MONO (-2340 2960);
DISPLAY INVISIBLE (-2340 2960);
FORCEPROP 1 LAST HDL_POWER P3V3_AUX
J 1
(-2350 3050);
DISPLAY 0.872340 (-2350 3050);
PAINT GREEN (-2350 3050);
FORCEPROP 2 LAST CDS_LIB pure_quanta_power
J 0
(-2350 3000);
PAINT MONO (-2350 3000);
DISPLAY INVISIBLE (-2350 3000);
FORCEPROP 1 LAST PATH I150
J 0
(-2300 3025);
DISPLAY 0.872340 (-2300 3025);
PAINT AQUA (-2300 3025);
DISPLAY INVISIBLE (-2300 3025);
FORCEADD UNIVERSAL_GND..1
(-1125 1825);
FORCEPROP 3 LASTPIN (-1125 1875) SIG_NAME GND\g
J 0
(-1115 1885);
DISPLAY 0.659574 (-1115 1885);
PAINT MONO (-1115 1885);
DISPLAY INVISIBLE (-1115 1885);
FORCEPROP 2 LAST CDS_LIB pure_quanta_power
J 0
(-1125 1825);
PAINT MONO (-1125 1825);
DISPLAY INVISIBLE (-1125 1825);
FORCEPROP 1 LAST HDL_POWER GND
J 1
(-1100 1750);
DISPLAY 0.872340 (-1100 1750);
PAINT GREEN (-1100 1750);
DISPLAY INVISIBLE (-1100 1750);
FORCEPROP 1 LAST PATH I151
J 0
(-1050 1825);
DISPLAY 0.872340 (-1050 1825);
PAINT AQUA (-1050 1825);
DISPLAY INVISIBLE (-1050 1825);
FORCEADD Q_RES..2
(-1125 2050);
FORCEPROP 1 LAST LOCATION R3232
J 0
(-1080 2175);
DISPLAY 0.787234 (-1080 2175);
FORCEPROP 2 LAST $SEC 1
J 0
(-1075 2275);
DISPLAY 0.680851 (-1075 2275);
PAINT MONO (-1075 2275);
DISPLAY INVISIBLE (-1075 2275);
FORCEPROP 2 LAST CDS_SEC 1
J 0
(-1075 2275);
DISPLAY 1.021277 (-1075 2275);
DISPLAY INVISIBLE (-1075 2275);
FORCEPROP 1 LASTPIN (-1125 2150) $PN 1
J 0
(-1120 2112);
DISPLAY 0.787234 (-1120 2112);
FORCEPROP 1 LASTPIN (-1125 1950) $PN 2
J 0
(-1120 1960);
DISPLAY 0.787234 (-1120 1960);
FORCEPROP 1 LAST MATERIAL CHIP
J 0
(-1085 1975);
DISPLAY 0.638298 (-1085 1975);
FORCEPROP 1 LAST VALUE 100K
J 0
(-1080 2125);
DISPLAY 0.638298 (-1080 2125);
FORCEPROP 1 LAST PACK_TYPE 0402LF
J 0
(-1085 1875);
DISPLAY 0.638298 (-1085 1875);
FORCEPROP 1 LAST TOLERANCE 1%
J 0
(-1080 2075);
DISPLAY 0.638298 (-1080 2075);
FORCEPROP 1 LAST WATTAGE 1/16W
J 0
(-1085 2025);
DISPLAY 0.638298 (-1085 2025);
FORCEPROP 2 LAST CDS_LIB pure_quanta
J 0
(-1125 2050);
PAINT MONO (-1125 2050);
DISPLAY INVISIBLE (-1125 2050);
FORCEPROP 1 LAST PATH I152
J 0
(-1075 2225);
DISPLAY 0.978723 (-1075 2225);
PAINT WHITE (-1075 2225);
DISPLAY INVISIBLE (-1075 2225);
FORCEPROP 1 LAST PART_NUMBER CS41002FB09
J 0
(-1085 1925);
DISPLAY 0.638298 (-1085 1925);
DISPLAY INVISIBLE (-1085 1925);
FORCEADD Q_RES..1
(-800 2275);
FORCEPROP 1 LAST LOCATION R3233
J 0
(-1025 2275);
DISPLAY 0.787234 (-1025 2275);
FORCEPROP 0 LAST $SEC 1
J 0
(-550 2400);
DISPLAY 0.680851 (-550 2400);
PAINT MONO (-550 2400);
DISPLAY INVISIBLE (-550 2400);
FORCEPROP 0 LAST CDS_SEC 1
J 0
(-550 2400);
DISPLAY 1.021277 (-550 2400);
DISPLAY INVISIBLE (-550 2400);
FORCEPROP 1 LASTPIN (-900 2275) $PN 1
J 0
(-888 2287);
DISPLAY 0.787234 (-888 2287);
PAINT MONO (-888 2287);
FORCEPROP 1 LASTPIN (-700 2275) $PN 2
J 0
(-738 2287);
DISPLAY 0.787234 (-738 2287);
PAINT MONO (-738 2287);
FORCEPROP 1 LAST VALUE 0
J 2
(-675 2275);
DISPLAY 0.510638 (-675 2275);
FORCEPROP 1 LAST TOLERANCE 5%
J 0
(-650 2275);
DISPLAY 0.510638 (-650 2275);
FORCEPROP 1 LAST WATTAGE 1/16W
J 2
(-550 2375);
DISPLAY 0.510638 (-550 2375);
FORCEPROP 1 LAST PACK_TYPE 0402LF
J 0
(-900 2375);
DISPLAY 0.510638 (-900 2375);
FORCEPROP 1 LAST MATERIAL CHIP
J 0
(-575 2275);
DISPLAY 0.510638 (-575 2275);
FORCEPROP 2 LAST CDS_LIB pure_quanta
J 0
(-800 2275);
DISPLAY INVISIBLE (-800 2275);
FORCEPROP 1 LAST PATH I153
J 0
(-850 2425);
DISPLAY 0.978723 (-850 2425);
PAINT WHITE (-850 2425);
DISPLAY INVISIBLE (-850 2425);
FORCEPROP 1 LAST PART_NUMBER CS00002JB13
J 0
(-900 2325);
DISPLAY 0.510638 (-900 2325);
DISPLAY INVISIBLE (-900 2325);
FORCEADD OFFPAGE..2
(100 2275);
FORCEPROP 2 LAST $XR0 131 
J 0
(289 2275);
DISPLAY 0.638298 (289 2275);
PAINT MONO (289 2275);
FORCEPROP 2 LAST CDS_LIB standard
J 0
(100 2275);
DISPLAY INVISIBLE (100 2275);
FORCEPROP 1 LAST OFFPAGE TRUE
J 0
(425 2150);
DISPLAY 0.872340 (425 2150);
PAINT GREEN (425 2150);
DISPLAY INVISIBLE (425 2150);
FORCEPROP 1 LAST COMMENT_BODY TRUE
J 0
(55 2180);
DISPLAY 0.872340 (55 2180);
PAINT GREEN (55 2180);
DISPLAY INVISIBLE (55 2180);
FORCEPROP 2 LAST PATH I154
J 0
(275 2350);
DISPLAY 1.021277 (275 2350);
DISPLAY INVISIBLE (275 2350);
FORCEADD Q_RES..1
R 1
(2900 6725);
FORCEPROP 1 LAST LOCATION R3237
J 0
(2950 6675);
DISPLAY 0.978723 (2950 6675);
FORCEPROP 0 LAST $SEC 1
R 1
J 0
(3000 6775);
DISPLAY 0.680851 (3000 6775);
PAINT MONO (3000 6775);
DISPLAY INVISIBLE (3000 6775);
FORCEPROP 0 LAST CDS_SEC 1
R 1
J 0
(3000 6775);
DISPLAY 1.021277 (3000 6775);
DISPLAY INVISIBLE (3000 6775);
FORCEPROP 1 LASTPIN (2900 6625) $PN 1
R 1
J 0
(2888 6637);
DISPLAY 0.787234 (2888 6637);
PAINT MONO (2888 6637);
FORCEPROP 1 LASTPIN (2900 6825) $PN 2
R 1
J 0
(2888 6787);
DISPLAY 0.787234 (2888 6787);
PAINT MONO (2888 6787);
FORCEPROP 1 LAST VALUE 0
J 2
(3000 6725);
DISPLAY 0.638298 (3000 6725);
FORCEPROP 1 LAST MATERIAL CHIP
J 0
(2950 6650);
DISPLAY 0.638298 (2950 6650);
FORCEPROP 2 LAST CDS_LIB pure_quanta
R 1
J 0
(2900 6725);
DISPLAY INVISIBLE (2900 6725);
FORCEPROP 1 LAST WATTAGE 1/16W
R 1
J 2
(3050 6700);
DISPLAY 0.510638 (3050 6700);
PAINT SKYBLUE (3050 6700);
DISPLAY INVISIBLE (3050 6700);
FORCEPROP 1 LAST PACK_TYPE 0402LF
R 1
J 0
(3050 6975);
DISPLAY 0.510638 (3050 6975);
PAINT SKYBLUE (3050 6975);
DISPLAY INVISIBLE (3050 6975);
FORCEPROP 1 LAST TOLERANCE 5%
R 1
J 0
(3000 6725);
DISPLAY 0.510638 (3000 6725);
PAINT SKYBLUE (3000 6725);
DISPLAY INVISIBLE (3000 6725);
FORCEPROP 1 LAST PATH I156
R 1
J 0
(2750 6675);
DISPLAY 0.978723 (2750 6675);
PAINT WHITE (2750 6675);
DISPLAY INVISIBLE (2750 6675);
FORCEPROP 1 LAST PART_NUMBER CS00002JB13
J 0
(2950 6600);
DISPLAY 0.510638 (2950 6600);
DISPLAY INVISIBLE (2950 6600);
FORCEADD 74LVC1G126SE7..1
(-1650 4000);
FORCEPROP 1 LAST LOCATION U66
J 0
(-1544 3831);
DISPLAY 0.723404 (-1544 3831);
PAINT GREEN (-1544 3831);
FORCEPROP 2 LAST SEC 1
J 0
(-1525 4225);
DISPLAY 0.680851 (-1525 4225);
PAINT MONO (-1525 4225);
DISPLAY INVISIBLE (-1525 4225);
FORCEPROP 2 LASTPIN (-1900 4050) $PN 2
J 2
(-1910 4060);
DISPLAY 0.680851 (-1910 4060);
PAINT MONO (-1910 4060);
FORCEPROP 2 LASTPIN (-1650 3750) $PN 3
R 1
J 2
(-1660 3740);
DISPLAY 0.680851 (-1660 3740);
PAINT MONO (-1660 3740);
FORCEPROP 2 LASTPIN (-1900 3950) $PN 1
J 2
(-1910 3960);
DISPLAY 0.680851 (-1910 3960);
PAINT MONO (-1910 3960);
FORCEPROP 2 LASTPIN (-1650 4250) $PN 5
R 1
J 0
(-1660 4260);
DISPLAY 0.680851 (-1660 4260);
PAINT MONO (-1660 4260);
FORCEPROP 2 LASTPIN (-1400 4000) $PN 4
J 0
(-1390 4010);
DISPLAY 0.680851 (-1390 4010);
PAINT MONO (-1390 4010);
FORCEPROP 2 LAST PART_TYPE SMLF
J 0
(-1525 4175);
DISPLAY 0.638298 (-1525 4175);
FORCEPROP 2 LAST VALUE 74LVC1G126SE-7
J 0
(-1525 4125);
DISPLAY 0.638298 (-1525 4125);
FORCEPROP 1 LAST MATERIAL IC
J 0
(-1544 3557);
DISPLAY 0.723404 (-1544 3557);
PAINT GREEN (-1544 3557);
FORCEPROP 2 LAST CDS_LIB pure_quanta
J 0
(-1650 4000);
DISPLAY INVISIBLE (-1650 4000);
FORCEPROP 1 LAST CDS_LMAN_SYM_OUTLINE -100,100,100,-100
J 0
(-1650 4000);
DISPLAY 0.468085 (-1650 4000);
PAINT GREEN (-1650 4000);
DISPLAY INVISIBLE (-1650 4000);
FORCEPROP 2 LAST SEC_TYPE 
J 0
(-1525 4225);
DISPLAY 1.021277 (-1525 4225);
DISPLAY INVISIBLE (-1525 4225);
FORCEPROP 1 LAST NEEDS_NO_SIZE TRUE
J 0
(-1650 4000);
DISPLAY 0.723404 (-1650 4000);
PAINT GREEN (-1650 4000);
DISPLAY INVISIBLE (-1650 4000);
FORCEPROP 1 LAST PATH I157
J 0
(-1650 4000);
DISPLAY 0.723404 (-1650 4000);
PAINT GREEN (-1650 4000);
DISPLAY INVISIBLE (-1650 4000);
FORCEPROP 1 LAST PART_NUMBER AL1G0126009
J 0
(-1544 3684);
DISPLAY 0.723404 (-1544 3684);
PAINT GREEN (-1544 3684);
DISPLAY INVISIBLE (-1544 3684);
FORCEADD UNIVERSAL_GND..1
(-1650 3625);
FORCEPROP 3 LASTPIN (-1650 3675) SIG_NAME GND\g
J 0
(-1640 3685);
DISPLAY 0.659574 (-1640 3685);
PAINT MONO (-1640 3685);
DISPLAY INVISIBLE (-1640 3685);
FORCEPROP 2 LAST CDS_LIB pure_quanta_power
J 0
(-1650 3625);
PAINT MONO (-1650 3625);
DISPLAY INVISIBLE (-1650 3625);
FORCEPROP 1 LAST HDL_POWER GND
J 1
(-1625 3550);
DISPLAY 0.872340 (-1625 3550);
PAINT GREEN (-1625 3550);
DISPLAY INVISIBLE (-1625 3550);
FORCEPROP 1 LAST PATH I158
J 0
(-1575 3625);
DISPLAY 0.872340 (-1575 3625);
PAINT AQUA (-1575 3625);
DISPLAY INVISIBLE (-1575 3625);
FORCEADD 74LVC1G126SE7..1
(-1975 2275);
FORCEPROP 1 LAST LOCATION U224
J 0
(-1869 2106);
DISPLAY 0.723404 (-1869 2106);
PAINT GREEN (-1869 2106);
FORCEPROP 0 LAST $SEC 1
J 0
(-1850 2500);
DISPLAY 0.680851 (-1850 2500);
PAINT MONO (-1850 2500);
DISPLAY INVISIBLE (-1850 2500);
FORCEPROP 0 LAST CDS_SEC 1
J 0
(-1850 2500);
DISPLAY 1.021277 (-1850 2500);
DISPLAY INVISIBLE (-1850 2500);
FORCEPROP 0 LASTPIN (-2225 2325) $PN 2
J 2
(-2235 2335);
DISPLAY 0.680851 (-2235 2335);
PAINT MONO (-2235 2335);
FORCEPROP 0 LASTPIN (-1975 2025) $PN 3
R 1
J 2
(-1985 2015);
DISPLAY 0.680851 (-1985 2015);
PAINT MONO (-1985 2015);
FORCEPROP 0 LASTPIN (-2225 2225) $PN 1
J 2
(-2235 2235);
DISPLAY 0.680851 (-2235 2235);
PAINT MONO (-2235 2235);
FORCEPROP 0 LASTPIN (-1975 2525) $PN 5
R 1
J 0
(-1985 2535);
DISPLAY 0.680851 (-1985 2535);
PAINT MONO (-1985 2535);
FORCEPROP 0 LASTPIN (-1725 2275) $PN 4
J 0
(-1715 2285);
DISPLAY 0.680851 (-1715 2285);
PAINT MONO (-1715 2285);
FORCEPROP 2 LAST PART_TYPE SMLF
J 0
(-1850 2450);
DISPLAY 0.638298 (-1850 2450);
FORCEPROP 2 LAST VALUE 74LVC1G126SE-7
J 0
(-1850 2400);
DISPLAY 0.638298 (-1850 2400);
FORCEPROP 1 LAST MATERIAL IC
J 0
(-1869 1832);
DISPLAY 0.723404 (-1869 1832);
PAINT GREEN (-1869 1832);
FORCEPROP 2 LAST CDS_LIB pure_quanta
J 0
(-1975 2275);
DISPLAY INVISIBLE (-1975 2275);
FORCEPROP 1 LAST CDS_LMAN_SYM_OUTLINE -100,100,100,-100
J 0
(-1975 2275);
DISPLAY 0.468085 (-1975 2275);
PAINT GREEN (-1975 2275);
DISPLAY INVISIBLE (-1975 2275);
FORCEPROP 1 LAST NEEDS_NO_SIZE TRUE
J 0
(-1975 2275);
DISPLAY 0.723404 (-1975 2275);
PAINT GREEN (-1975 2275);
DISPLAY INVISIBLE (-1975 2275);
FORCEPROP 1 LAST PATH I159
J 0
(-1975 2275);
DISPLAY 0.723404 (-1975 2275);
PAINT GREEN (-1975 2275);
DISPLAY INVISIBLE (-1975 2275);
FORCEPROP 1 LAST PART_NUMBER AL1G0126009
J 0
(-1869 1959);
DISPLAY 0.723404 (-1869 1959);
PAINT GREEN (-1869 1959);
DISPLAY INVISIBLE (-1869 1959);
FORCEADD Q_CAP..1
R 2
(-975 5800);
FORCEPROP 1 LAST LOCATION C641
J 2
(-1025 5900);
DISPLAY 0.978723 (-1025 5900);
FORCEPROP 2 LAST $SEC 1
J 0
(-1025 6000);
DISPLAY 0.680851 (-1025 6000);
PAINT MONO (-1025 6000);
DISPLAY INVISIBLE (-1025 6000);
FORCEPROP 2 LAST CDS_SEC 1
J 0
(-1025 6000);
DISPLAY 1.021277 (-1025 6000);
DISPLAY INVISIBLE (-1025 6000);
FORCEPROP 1 LASTPIN (-975 5900) $PN 1
J 2
(-985 5880);
DISPLAY 0.787234 (-985 5880);
FORCEPROP 1 LASTPIN (-975 5700) $PN 2
J 2
(-985 5680);
DISPLAY 0.787234 (-985 5680);
FORCEPROP 1 LAST TOLERANCE 10%
J 2
(-1025 5750);
DISPLAY 0.510638 (-1025 5750);
FORCEPROP 1 LAST PACK_TYPE 0402
J 2
(-1025 5600);
DISPLAY 0.510638 (-1025 5600);
FORCEPROP 1 LAST MATERIAL X7R
J 2
(-1025 5700);
DISPLAY 0.510638 (-1025 5700);
FORCEPROP 1 LAST VOLTAGE 25V
J 2
(-1025 5800);
DISPLAY 0.510638 (-1025 5800);
FORCEPROP 1 LAST VALUE 0.1UF
J 2
(-1025 5850);
DISPLAY 0.510638 (-1025 5850);
FORCEPROP 2 LAST CDS_LIB pure_quanta
J 0
(-975 5800);
PAINT MONO (-975 5800);
DISPLAY INVISIBLE (-975 5800);
FORCEPROP 1 LAST PATH I16
J 2
(-1025 5950);
DISPLAY 0.978723 (-1025 5950);
PAINT WHITE (-1025 5950);
DISPLAY INVISIBLE (-1025 5950);
FORCEPROP 1 LAST PART_NUMBER CH4104K1B00
J 2
(-1025 5650);
DISPLAY 0.510638 (-1025 5650);
DISPLAY INVISIBLE (-1025 5650);
FORCEADD Q_RES..1
(-3350 2225);
FORCEPROP 1 LAST LOCATION R3231
J 0
(-3600 2225);
DISPLAY 0.638298 (-3600 2225);
FORCEPROP 2 LAST $SEC 1
J 0
(-3400 2425);
DISPLAY 0.680851 (-3400 2425);
PAINT MONO (-3400 2425);
DISPLAY INVISIBLE (-3400 2425);
FORCEPROP 2 LAST CDS_SEC 1
J 0
(-3400 2425);
DISPLAY 1.021277 (-3400 2425);
DISPLAY INVISIBLE (-3400 2425);
FORCEPROP 1 LASTPIN (-3450 2225) $PN 1
J 0
(-3438 2237);
DISPLAY 0.787234 (-3438 2237);
FORCEPROP 1 LASTPIN (-3250 2225) $PN 2
J 0
(-3288 2237);
DISPLAY 0.787234 (-3288 2237);
FORCEPROP 1 LAST PACK_TYPE 0402LF
J 0
(-3450 2150);
DISPLAY 0.510638 (-3450 2150);
FORCEPROP 1 LAST WATTAGE 1/16W
J 2
(-3175 2100);
DISPLAY 0.510638 (-3175 2100);
FORCEPROP 1 LAST VALUE 33.2
J 2
(-3150 2225);
DISPLAY 0.510638 (-3150 2225);
FORCEPROP 1 LAST TOLERANCE 1%
J 0
(-3125 2225);
DISPLAY 0.510638 (-3125 2225);
FORCEPROP 1 LAST MATERIAL CHIP
J 0
(-3450 2100);
DISPLAY 0.510638 (-3450 2100);
FORCEPROP 2 LAST CDS_LIB pure_quanta
J 0
(-3350 2225);
PAINT MONO (-3350 2225);
DISPLAY INVISIBLE (-3350 2225);
FORCEPROP 1 LAST PATH I160
J 0
(-3400 2375);
DISPLAY 0.978723 (-3400 2375);
PAINT WHITE (-3400 2375);
DISPLAY INVISIBLE (-3400 2375);
FORCEPROP 1 LAST PART_NUMBER CS03322FB03
J 0
(-3450 2050);
DISPLAY 0.510638 (-3450 2050);
DISPLAY INVISIBLE (-3450 2050);
FORCEADD OFFPAGE..1
(-4300 2225);
FORCEPROP 2 LAST $XR2 132 
J 0
(-4822 2225);
DISPLAY 0.638298 (-4822 2225);
PAINT MONO (-4822 2225);
FORCEPROP 2 LAST $XR1 136 
J 0
(-4702 2225);
DISPLAY 0.638298 (-4702 2225);
PAINT MONO (-4702 2225);
FORCEPROP 2 LAST $XR0 131 
J 0
(-4582 2225);
DISPLAY 0.638298 (-4582 2225);
PAINT MONO (-4582 2225);
FORCEPROP 2 LAST CDS_LIB standard
J 0
(-4300 2225);
PAINT MONO (-4300 2225);
DISPLAY INVISIBLE (-4300 2225);
FORCEPROP 1 LAST OFFPAGE TRUE
J 0
(-3975 2100);
DISPLAY 0.872340 (-3975 2100);
PAINT GREEN (-3975 2100);
DISPLAY INVISIBLE (-3975 2100);
FORCEPROP 1 LAST COMMENT_BODY TRUE
J 0
(-4175 2125);
DISPLAY 0.872340 (-4175 2125);
PAINT GREEN (-4175 2125);
DISPLAY INVISIBLE (-4175 2125);
FORCEPROP 2 LAST PATH I161
J 0
(-4550 2275);
DISPLAY 1.021277 (-4550 2275);
DISPLAY INVISIBLE (-4550 2275);
FORCEADD UNIVERSAL_GND..1
(-1975 1900);
FORCEPROP 3 LASTPIN (-1975 1950) SIG_NAME GND\g
J 0
(-1965 1960);
DISPLAY 0.659574 (-1965 1960);
PAINT MONO (-1965 1960);
DISPLAY INVISIBLE (-1965 1960);
FORCEPROP 2 LAST CDS_LIB pure_quanta_power
J 0
(-1975 1900);
PAINT MONO (-1975 1900);
DISPLAY INVISIBLE (-1975 1900);
FORCEPROP 1 LAST HDL_POWER GND
J 1
(-1950 1825);
DISPLAY 0.872340 (-1950 1825);
PAINT GREEN (-1950 1825);
DISPLAY INVISIBLE (-1950 1825);
FORCEPROP 1 LAST PATH I162
J 0
(-1900 1900);
DISPLAY 0.872340 (-1900 1900);
PAINT AQUA (-1900 1900);
DISPLAY INVISIBLE (-1900 1900);
FORCEADD OFFPAGE..5
R 2
(600 4000);
FORCEPROP 2 LAST $XR0 133 
J 0
(789 4000);
DISPLAY 0.638298 (789 4000);
PAINT MONO (789 4000);
FORCEPROP 2 LAST CDS_LIB standard
J 2
(600 4000);
DISPLAY INVISIBLE (600 4000);
FORCEPROP 1 LAST OFFPAGE TRUE
J 2
(275 3875);
DISPLAY 0.872340 (275 3875);
PAINT GREEN (275 3875);
DISPLAY INVISIBLE (275 3875);
FORCEPROP 1 LAST COMMENT_BODY TRUE
J 2
(500 3925);
DISPLAY 0.872340 (500 3925);
PAINT GREEN (500 3925);
DISPLAY INVISIBLE (500 3925);
FORCEPROP 2 LAST PATH I163
J 2
(550 4075);
DISPLAY 1.021277 (550 4075);
DISPLAY INVISIBLE (550 4075);
FORCEADD Q_RES..1
(-425 4000);
FORCEPROP 1 LAST LOCATION R2473
J 0
(-650 4000);
DISPLAY 0.787234 (-650 4000);
FORCEPROP 0 LAST $SEC 1
J 0
(-175 4125);
DISPLAY 0.680851 (-175 4125);
PAINT MONO (-175 4125);
DISPLAY INVISIBLE (-175 4125);
FORCEPROP 0 LAST CDS_SEC 1
J 0
(-175 4125);
DISPLAY 0.680851 (-175 4125);
DISPLAY INVISIBLE (-175 4125);
FORCEPROP 1 LASTPIN (-525 4000) $PN 1
J 0
(-513 4012);
DISPLAY 0.787234 (-513 4012);
PAINT MONO (-513 4012);
FORCEPROP 1 LASTPIN (-325 4000) $PN 2
J 0
(-363 4012);
DISPLAY 0.787234 (-363 4012);
PAINT MONO (-363 4012);
FORCEPROP 1 LAST TOLERANCE 5%
J 0
(-275 4000);
DISPLAY 0.510638 (-275 4000);
FORCEPROP 1 LAST PACK_TYPE 0402LF
J 0
(-525 4100);
DISPLAY 0.510638 (-525 4100);
FORCEPROP 1 LAST MATERIAL CHIP
J 0
(-200 4000);
DISPLAY 0.510638 (-200 4000);
FORCEPROP 1 LAST WATTAGE 1/16W
J 2
(-175 4100);
DISPLAY 0.510638 (-175 4100);
FORCEPROP 1 LAST VALUE 0
J 2
(-300 4000);
DISPLAY 0.510638 (-300 4000);
FORCEPROP 2 LAST CDS_LIB pure_quanta
J 0
(-425 4000);
DISPLAY INVISIBLE (-425 4000);
FORCEPROP 1 LAST PATH I164
J 0
(-475 4150);
DISPLAY 0.978723 (-475 4150);
PAINT WHITE (-475 4150);
DISPLAY INVISIBLE (-475 4150);
FORCEPROP 1 LAST PART_NUMBER CS00002JB13
J 0
(-525 4050);
DISPLAY 0.510638 (-525 4050);
DISPLAY INVISIBLE (-525 4050);
FORCEADD Q_RES..1
(-525 3475);
FORCEPROP 1 LAST LOCATION R2474
J 0
(-750 3475);
DISPLAY 0.787234 (-750 3475);
FORCEPROP 0 LAST $SEC 1
J 0
(-275 3600);
DISPLAY 0.680851 (-275 3600);
PAINT MONO (-275 3600);
DISPLAY INVISIBLE (-275 3600);
FORCEPROP 0 LAST CDS_SEC 1
J 0
(-275 3600);
DISPLAY 0.680851 (-275 3600);
DISPLAY INVISIBLE (-275 3600);
FORCEPROP 1 LASTPIN (-625 3475) $PN 1
J 0
(-613 3487);
DISPLAY 0.787234 (-613 3487);
PAINT MONO (-613 3487);
FORCEPROP 1 LASTPIN (-425 3475) $PN 2
J 0
(-463 3487);
DISPLAY 0.787234 (-463 3487);
PAINT MONO (-463 3487);
FORCEPROP 1 LAST TOLERANCE 5%
J 0
(-375 3475);
DISPLAY 0.510638 (-375 3475);
FORCEPROP 1 LAST MATERIAL EMPTY
J 0
(-300 3475);
DISPLAY 0.510638 (-300 3475);
PAINT RED (-300 3475);
FORCEPROP 1 LAST VALUE 0
J 2
(-400 3475);
DISPLAY 0.510638 (-400 3475);
FORCEPROP 1 LAST PACK_TYPE 0402LF
J 0
(-625 3575);
DISPLAY 0.510638 (-625 3575);
FORCEPROP 1 LAST WATTAGE 1/16W
J 2
(-275 3575);
DISPLAY 0.510638 (-275 3575);
FORCEPROP 2 LAST CDS_LIB pure_quanta
J 0
(-525 3475);
DISPLAY INVISIBLE (-525 3475);
FORCEPROP 1 LAST PATH I165
J 0
(-575 3625);
DISPLAY 0.978723 (-575 3625);
PAINT WHITE (-575 3625);
DISPLAY INVISIBLE (-575 3625);
FORCEPROP 1 LAST PART_NUMBER CS00002JB13
J 0
(-625 3525);
DISPLAY 0.510638 (-625 3525);
DISPLAY INVISIBLE (-625 3525);
FORCEADD 74CBTLV3126PW..1
R 2
(-225 5275);
FORCEPROP 1 LAST LOCATION U7
J 2
(23 5733);
DISPLAY 0.723404 (23 5733);
PAINT GREEN (23 5733);
FORCEPROP 2 LAST $SEC 1
J 0
(0 5875);
DISPLAY 0.680851 (0 5875);
PAINT MONO (0 5875);
DISPLAY INVISIBLE (0 5875);
FORCEPROP 2 LAST CDS_SEC 1
J 0
(0 5875);
DISPLAY 1.021277 (0 5875);
DISPLAY INVISIBLE (0 5875);
FORCEPROP 2 LASTPIN (175 5025) $PN 2
J 0
(185 5035);
DISPLAY 0.808511 (185 5035);
FORCEPROP 2 LASTPIN (-625 5025) $PN 3
J 2
(-635 5035);
DISPLAY 0.808511 (-635 5035);
FORCEPROP 2 LASTPIN (175 4975) $PN 1
J 0
(185 4985);
DISPLAY 0.808511 (185 4985);
FORCEPROP 2 LASTPIN (175 5175) $PN 5
J 0
(185 5185);
DISPLAY 0.808511 (185 5185);
FORCEPROP 2 LASTPIN (-625 5175) $PN 6
J 2
(-635 5185);
DISPLAY 0.808511 (-635 5185);
FORCEPROP 2 LASTPIN (175 5125) $PN 4
J 0
(185 5135);
DISPLAY 0.808511 (185 5135);
FORCEPROP 2 LASTPIN (175 5325) $PN 9
J 0
(185 5335);
DISPLAY 0.808511 (185 5335);
FORCEPROP 2 LASTPIN (-625 5325) $PN 8
J 2
(-635 5335);
DISPLAY 0.808511 (-635 5335);
FORCEPROP 2 LASTPIN (175 5275) $PN 10
J 0
(185 5285);
DISPLAY 0.808511 (185 5285);
FORCEPROP 2 LASTPIN (175 5475) $PN 12
J 0
(185 5485);
DISPLAY 0.808511 (185 5485);
FORCEPROP 2 LASTPIN (-625 5475) $PN 11
J 2
(-635 5485);
DISPLAY 0.808511 (-635 5485);
FORCEPROP 2 LASTPIN (175 5425) $PN 13
J 0
(185 5435);
DISPLAY 0.808511 (185 5435);
FORCEPROP 2 LASTPIN (-625 4975) $PN 7
J 2
(-635 4985);
DISPLAY 0.808511 (-635 4985);
FORCEPROP 2 LASTPIN (-625 5525) $PN 14
J 2
(-635 5535);
DISPLAY 0.808511 (-635 5535);
FORCEPROP 2 LAST PART_TYPE SMLF
J 2
(0 5825);
DISPLAY 1.021277 (0 5825);
FORCEPROP 1 LAST MATERIAL IC
J 2
(23 5628);
DISPLAY 0.723404 (23 5628);
PAINT GREEN (23 5628);
FORCEPROP 2 LAST VALUE 74CBTLV3126PW
J 2
(0 5775);
DISPLAY 1.021277 (0 5775);
FORCEPROP 2 LAST CDS_LIB pure_quanta
J 2
(-225 5275);
PAINT MONO (-225 5275);
DISPLAY INVISIBLE (-225 5275);
FORCEPROP 1 LAST NEEDS_NO_SIZE TRUE
J 2
(-475 4965);
DISPLAY 0.723404 (-475 4965);
PAINT GREEN (-475 4965);
DISPLAY INVISIBLE (-475 4965);
FORCEPROP 1 LAST CDS_LMAN_SYM_OUTLINE -250,350,250,-350
J 2
(-225 5275);
DISPLAY 0.468085 (-225 5275);
PAINT GREEN (-225 5275);
DISPLAY INVISIBLE (-225 5275);
FORCEPROP 1 LAST PATH I2
J 2
(-475 4925);
DISPLAY 0.723404 (-475 4925);
PAINT GREEN (-475 4925);
DISPLAY INVISIBLE (-475 4925);
FORCEPROP 1 LAST PART_NUMBER AL003126K08
J 2
(23 5683);
DISPLAY 0.723404 (23 5683);
PAINT GREEN (23 5683);
DISPLAY INVISIBLE (23 5683);
FORCEADD OFFPAGE..1
(-1625 6450);
FORCEPROP 2 LAST $XR0 131 
J 0
(-1907 6450);
DISPLAY 0.638298 (-1907 6450);
PAINT MONO (-1907 6450);
FORCEPROP 2 LAST CDS_LIB standard
J 0
(-1625 6450);
PAINT MONO (-1625 6450);
DISPLAY INVISIBLE (-1625 6450);
FORCEPROP 1 LAST OFFPAGE TRUE
J 0
(-1300 6325);
DISPLAY 0.872340 (-1300 6325);
PAINT GREEN (-1300 6325);
DISPLAY INVISIBLE (-1300 6325);
FORCEPROP 1 LAST COMMENT_BODY TRUE
J 0
(-1500 6350);
DISPLAY 0.872340 (-1500 6350);
PAINT GREEN (-1500 6350);
DISPLAY INVISIBLE (-1500 6350);
FORCEPROP 2 LAST PATH I35
J 0
(-1575 6525);
DISPLAY 1.021277 (-1575 6525);
DISPLAY INVISIBLE (-1575 6525);
FORCEADD OFFPAGE..1
(-1625 6900);
FORCEPROP 2 LAST $XR0 131 
J 0
(-1907 6900);
DISPLAY 0.638298 (-1907 6900);
PAINT MONO (-1907 6900);
FORCEPROP 2 LAST CDS_LIB standard
J 0
(-1625 6900);
PAINT MONO (-1625 6900);
DISPLAY INVISIBLE (-1625 6900);
FORCEPROP 1 LAST OFFPAGE TRUE
J 0
(-1300 6775);
DISPLAY 0.872340 (-1300 6775);
PAINT GREEN (-1300 6775);
DISPLAY INVISIBLE (-1300 6775);
FORCEPROP 1 LAST COMMENT_BODY TRUE
J 0
(-1500 6800);
DISPLAY 0.872340 (-1500 6800);
PAINT GREEN (-1500 6800);
DISPLAY INVISIBLE (-1500 6800);
FORCEPROP 2 LAST PATH I36
J 0
(-1575 6975);
DISPLAY 1.021277 (-1575 6975);
DISPLAY INVISIBLE (-1575 6975);
FORCEADD OFFPAGE..1
(-1625 6750);
FORCEPROP 2 LAST $XR0 131 
J 0
(-1907 6750);
DISPLAY 0.638298 (-1907 6750);
PAINT MONO (-1907 6750);
FORCEPROP 2 LAST CDS_LIB standard
J 0
(-1625 6750);
PAINT MONO (-1625 6750);
DISPLAY INVISIBLE (-1625 6750);
FORCEPROP 1 LAST OFFPAGE TRUE
J 0
(-1300 6625);
DISPLAY 0.872340 (-1300 6625);
PAINT GREEN (-1300 6625);
DISPLAY INVISIBLE (-1300 6625);
FORCEPROP 1 LAST COMMENT_BODY TRUE
J 0
(-1500 6650);
DISPLAY 0.872340 (-1500 6650);
PAINT GREEN (-1500 6650);
DISPLAY INVISIBLE (-1500 6650);
FORCEPROP 2 LAST PATH I37
J 0
(-1575 6825);
DISPLAY 1.021277 (-1575 6825);
DISPLAY INVISIBLE (-1575 6825);
FORCEADD OFFPAGE..1
(-1625 6600);
FORCEPROP 2 LAST $XR0 131 
J 0
(-1907 6600);
DISPLAY 0.638298 (-1907 6600);
PAINT MONO (-1907 6600);
FORCEPROP 2 LAST CDS_LIB standard
J 0
(-1625 6600);
PAINT MONO (-1625 6600);
DISPLAY INVISIBLE (-1625 6600);
FORCEPROP 1 LAST OFFPAGE TRUE
J 0
(-1300 6475);
DISPLAY 0.872340 (-1300 6475);
PAINT GREEN (-1300 6475);
DISPLAY INVISIBLE (-1300 6475);
FORCEPROP 1 LAST COMMENT_BODY TRUE
J 0
(-1500 6500);
DISPLAY 0.872340 (-1500 6500);
PAINT GREEN (-1500 6500);
DISPLAY INVISIBLE (-1500 6500);
FORCEPROP 2 LAST PATH I38
J 0
(-1575 6675);
DISPLAY 1.021277 (-1575 6675);
DISPLAY INVISIBLE (-1575 6675);
FORCEADD OFFPAGE..5
(-1625 5475);
FORCEPROP 2 LAST $XR0 131 
J 0
(-1880 5475);
DISPLAY 0.638298 (-1880 5475);
PAINT MONO (-1880 5475);
FORCEPROP 2 LAST CDS_LIB standard
J 0
(-1625 5475);
PAINT MONO (-1625 5475);
DISPLAY INVISIBLE (-1625 5475);
FORCEPROP 1 LAST OFFPAGE TRUE
J 0
(-1300 5350);
DISPLAY 0.872340 (-1300 5350);
PAINT GREEN (-1300 5350);
DISPLAY INVISIBLE (-1300 5350);
FORCEPROP 1 LAST COMMENT_BODY TRUE
J 0
(-1525 5400);
DISPLAY 0.872340 (-1525 5400);
PAINT GREEN (-1525 5400);
DISPLAY INVISIBLE (-1525 5400);
FORCEPROP 2 LAST PATH I39
J 0
(-1575 5550);
DISPLAY 1.021277 (-1575 5550);
DISPLAY INVISIBLE (-1575 5550);
FORCEADD OFFPAGE..5
(-1625 5325);
FORCEPROP 2 LAST $XR0 131 
J 0
(-1880 5325);
DISPLAY 0.638298 (-1880 5325);
PAINT MONO (-1880 5325);
FORCEPROP 2 LAST CDS_LIB standard
J 0
(-1625 5325);
PAINT MONO (-1625 5325);
DISPLAY INVISIBLE (-1625 5325);
FORCEPROP 1 LAST OFFPAGE TRUE
J 0
(-1300 5200);
DISPLAY 0.872340 (-1300 5200);
PAINT GREEN (-1300 5200);
DISPLAY INVISIBLE (-1300 5200);
FORCEPROP 1 LAST COMMENT_BODY TRUE
J 0
(-1525 5250);
DISPLAY 0.872340 (-1525 5250);
PAINT GREEN (-1525 5250);
DISPLAY INVISIBLE (-1525 5250);
FORCEPROP 2 LAST PATH I40
J 0
(-1575 5400);
DISPLAY 1.021277 (-1575 5400);
DISPLAY INVISIBLE (-1575 5400);
FORCEADD OFFPAGE..5
(-1625 5175);
FORCEPROP 2 LAST $XR0 131 
J 0
(-1880 5175);
DISPLAY 0.638298 (-1880 5175);
PAINT MONO (-1880 5175);
FORCEPROP 2 LAST CDS_LIB standard
J 0
(-1625 5175);
PAINT MONO (-1625 5175);
DISPLAY INVISIBLE (-1625 5175);
FORCEPROP 1 LAST OFFPAGE TRUE
J 0
(-1300 5050);
DISPLAY 0.872340 (-1300 5050);
PAINT GREEN (-1300 5050);
DISPLAY INVISIBLE (-1300 5050);
FORCEPROP 1 LAST COMMENT_BODY TRUE
J 0
(-1525 5100);
DISPLAY 0.872340 (-1525 5100);
PAINT GREEN (-1525 5100);
DISPLAY INVISIBLE (-1525 5100);
FORCEPROP 2 LAST PATH I41
J 0
(-1575 5250);
DISPLAY 1.021277 (-1575 5250);
DISPLAY INVISIBLE (-1575 5250);
FORCEADD OFFPAGE..5
(-1625 5025);
FORCEPROP 2 LAST $XR0 131 
J 0
(-1880 5025);
DISPLAY 0.638298 (-1880 5025);
PAINT MONO (-1880 5025);
FORCEPROP 2 LAST CDS_LIB standard
J 0
(-1625 5025);
PAINT MONO (-1625 5025);
DISPLAY INVISIBLE (-1625 5025);
FORCEPROP 1 LAST OFFPAGE TRUE
J 0
(-1300 4900);
DISPLAY 0.872340 (-1300 4900);
PAINT GREEN (-1300 4900);
DISPLAY INVISIBLE (-1300 4900);
FORCEPROP 1 LAST COMMENT_BODY TRUE
J 0
(-1525 4950);
DISPLAY 0.872340 (-1525 4950);
PAINT GREEN (-1525 4950);
DISPLAY INVISIBLE (-1525 4950);
FORCEPROP 2 LAST PATH I42
J 0
(-1575 5100);
DISPLAY 1.021277 (-1575 5100);
DISPLAY INVISIBLE (-1575 5100);
FORCEADD UNIVERSAL_POWER..1
(-775 6125);
FORCEPROP 3 LASTPIN (-775 6075) SIG_NAME P3V3_AUX\g
J 0
(-765 6085);
DISPLAY 0.659574 (-765 6085);
PAINT MONO (-765 6085);
DISPLAY INVISIBLE (-765 6085);
FORCEPROP 1 LAST HDL_POWER P3V3_AUX
J 1
(-775 6175);
DISPLAY 0.872340 (-775 6175);
PAINT GREEN (-775 6175);
FORCEPROP 2 LAST CDS_LIB pure_quanta_power
J 0
(-775 6125);
PAINT MONO (-775 6125);
DISPLAY INVISIBLE (-775 6125);
FORCEPROP 1 LAST PATH I43
J 0
(-725 6150);
DISPLAY 0.872340 (-725 6150);
PAINT AQUA (-725 6150);
DISPLAY INVISIBLE (-725 6150);
FORCEADD UNIVERSAL_GND..1
(-775 4850);
FORCEPROP 3 LASTPIN (-775 4900) SIG_NAME GND\g
J 0
(-765 4910);
DISPLAY 0.659574 (-765 4910);
PAINT MONO (-765 4910);
DISPLAY INVISIBLE (-765 4910);
FORCEPROP 2 LAST CDS_LIB pure_quanta_power
J 0
(-775 4850);
PAINT MONO (-775 4850);
DISPLAY INVISIBLE (-775 4850);
FORCEPROP 1 LAST HDL_POWER GND
J 1
(-750 4775);
DISPLAY 0.872340 (-750 4775);
PAINT GREEN (-750 4775);
DISPLAY INVISIBLE (-750 4775);
FORCEPROP 1 LAST PATH I44
J 0
(-700 4850);
DISPLAY 0.872340 (-700 4850);
PAINT AQUA (-700 4850);
DISPLAY INVISIBLE (-700 4850);
FORCEADD UNIVERSAL_GND..1
(-775 6275);
FORCEPROP 3 LASTPIN (-775 6325) SIG_NAME GND\g
J 0
(-765 6335);
DISPLAY 0.659574 (-765 6335);
PAINT MONO (-765 6335);
DISPLAY INVISIBLE (-765 6335);
FORCEPROP 2 LAST CDS_LIB pure_quanta_power
J 0
(-775 6275);
PAINT MONO (-775 6275);
DISPLAY INVISIBLE (-775 6275);
FORCEPROP 1 LAST HDL_POWER GND
J 1
(-750 6200);
DISPLAY 0.872340 (-750 6200);
PAINT GREEN (-750 6200);
DISPLAY INVISIBLE (-750 6200);
FORCEPROP 1 LAST PATH I45
J 0
(-700 6275);
DISPLAY 0.872340 (-700 6275);
PAINT AQUA (-700 6275);
DISPLAY INVISIBLE (-700 6275);
FORCEADD UNIVERSAL_POWER..1
(-775 7550);
FORCEPROP 3 LASTPIN (-775 7500) SIG_NAME P3V3_AUX\g
J 0
(-765 7510);
DISPLAY 0.659574 (-765 7510);
PAINT MONO (-765 7510);
DISPLAY INVISIBLE (-765 7510);
FORCEPROP 1 LAST HDL_POWER P3V3_AUX
J 1
(-775 7600);
DISPLAY 0.872340 (-775 7600);
PAINT GREEN (-775 7600);
FORCEPROP 2 LAST CDS_LIB pure_quanta_power
J 0
(-775 7550);
PAINT MONO (-775 7550);
DISPLAY INVISIBLE (-775 7550);
FORCEPROP 1 LAST PATH I46
J 0
(-725 7575);
DISPLAY 0.872340 (-725 7575);
PAINT AQUA (-725 7575);
DISPLAY INVISIBLE (-725 7575);
FORCEADD Q_CAP..1
R 2
(-975 7225);
FORCEPROP 1 LAST LOCATION C640
J 2
(-1025 7325);
DISPLAY 0.978723 (-1025 7325);
FORCEPROP 2 LAST $SEC 1
J 0
(-1025 7425);
DISPLAY 0.680851 (-1025 7425);
PAINT MONO (-1025 7425);
DISPLAY INVISIBLE (-1025 7425);
FORCEPROP 2 LAST CDS_SEC 1
J 0
(-1025 7425);
DISPLAY 1.021277 (-1025 7425);
DISPLAY INVISIBLE (-1025 7425);
FORCEPROP 1 LASTPIN (-975 7325) $PN 1
J 2
(-985 7305);
DISPLAY 0.787234 (-985 7305);
FORCEPROP 1 LASTPIN (-975 7125) $PN 2
J 2
(-985 7105);
DISPLAY 0.787234 (-985 7105);
FORCEPROP 1 LAST VOLTAGE 25V
J 2
(-1025 7225);
DISPLAY 0.510638 (-1025 7225);
FORCEPROP 1 LAST VALUE 0.1UF
J 2
(-1025 7275);
DISPLAY 0.510638 (-1025 7275);
FORCEPROP 1 LAST MATERIAL X7R
J 2
(-1025 7125);
DISPLAY 0.510638 (-1025 7125);
FORCEPROP 1 LAST PACK_TYPE 0402
J 2
(-1025 7025);
DISPLAY 0.510638 (-1025 7025);
FORCEPROP 1 LAST TOLERANCE 10%
J 2
(-1025 7175);
DISPLAY 0.510638 (-1025 7175);
FORCEPROP 2 LAST CDS_LIB pure_quanta
J 0
(-975 7225);
PAINT MONO (-975 7225);
DISPLAY INVISIBLE (-975 7225);
FORCEPROP 1 LAST PATH I47
J 2
(-1025 7375);
DISPLAY 0.978723 (-1025 7375);
PAINT WHITE (-1025 7375);
DISPLAY INVISIBLE (-1025 7375);
FORCEPROP 1 LAST PART_NUMBER CH4104K1B00
J 2
(-1025 7075);
DISPLAY 0.510638 (-1025 7075);
DISPLAY INVISIBLE (-1025 7075);
FORCEADD UNIVERSAL_GND..1
(-975 7000);
FORCEPROP 3 LASTPIN (-975 7050) SIG_NAME GND\g
J 0
(-965 7060);
DISPLAY 0.659574 (-965 7060);
PAINT MONO (-965 7060);
DISPLAY INVISIBLE (-965 7060);
FORCEPROP 2 LAST CDS_LIB pure_quanta_power
J 0
(-975 7000);
PAINT MONO (-975 7000);
DISPLAY INVISIBLE (-975 7000);
FORCEPROP 1 LAST HDL_POWER GND
J 1
(-950 6925);
DISPLAY 0.872340 (-950 6925);
PAINT GREEN (-950 6925);
DISPLAY INVISIBLE (-950 6925);
FORCEPROP 1 LAST PATH I48
J 0
(-900 7000);
DISPLAY 0.872340 (-900 7000);
PAINT AQUA (-900 7000);
DISPLAY INVISIBLE (-900 7000);
FORCEADD UNIVERSAL_POWER..1
(-2075 4650);
FORCEPROP 3 LASTPIN (-2075 4600) SIG_NAME P3V3_AUX\g
J 0
(-2065 4610);
DISPLAY 0.659574 (-2065 4610);
PAINT MONO (-2065 4610);
DISPLAY INVISIBLE (-2065 4610);
FORCEPROP 1 LAST HDL_POWER P3V3_AUX
J 1
(-2075 4700);
DISPLAY 0.872340 (-2075 4700);
PAINT GREEN (-2075 4700);
FORCEPROP 2 LAST CDS_LIB pure_quanta_power
J 0
(-2075 4650);
PAINT MONO (-2075 4650);
DISPLAY INVISIBLE (-2075 4650);
FORCEPROP 1 LAST PATH I54
J 0
(-2025 4675);
DISPLAY 0.872340 (-2025 4675);
PAINT AQUA (-2025 4675);
DISPLAY INVISIBLE (-2025 4675);
FORCEADD Q_RES..2
(-175 3800);
FORCEPROP 1 LAST LOCATION R1289
J 0
(-130 3925);
DISPLAY 0.787234 (-130 3925);
FORCEPROP 2 LAST $SEC 1
J 0
(-125 4025);
DISPLAY 0.680851 (-125 4025);
PAINT MONO (-125 4025);
DISPLAY INVISIBLE (-125 4025);
FORCEPROP 2 LAST CDS_SEC 1
J 0
(-125 4025);
DISPLAY 1.021277 (-125 4025);
DISPLAY INVISIBLE (-125 4025);
FORCEPROP 1 LASTPIN (-175 3900) $PN 1
J 0
(-170 3862);
DISPLAY 0.787234 (-170 3862);
FORCEPROP 1 LASTPIN (-175 3700) $PN 2
J 0
(-170 3710);
DISPLAY 0.787234 (-170 3710);
FORCEPROP 1 LAST WATTAGE 1/16W
J 0
(-135 3775);
DISPLAY 0.638298 (-135 3775);
FORCEPROP 1 LAST VALUE 100K
J 0
(-130 3875);
DISPLAY 0.638298 (-130 3875);
FORCEPROP 1 LAST MATERIAL CHIP
J 0
(-135 3725);
DISPLAY 0.638298 (-135 3725);
FORCEPROP 1 LAST TOLERANCE 1%
J 0
(-130 3825);
DISPLAY 0.638298 (-130 3825);
FORCEPROP 1 LAST PACK_TYPE 0402LF
J 0
(-135 3625);
DISPLAY 0.638298 (-135 3625);
FORCEPROP 2 LAST CDS_LIB pure_quanta
J 0
(-175 3800);
PAINT MONO (-175 3800);
DISPLAY INVISIBLE (-175 3800);
FORCEPROP 1 LAST PATH I56
J 0
(-125 3975);
DISPLAY 0.978723 (-125 3975);
PAINT WHITE (-125 3975);
DISPLAY INVISIBLE (-125 3975);
FORCEPROP 1 LAST PART_NUMBER CS41002FB09
J 0
(-135 3675);
DISPLAY 0.638298 (-135 3675);
DISPLAY INVISIBLE (-135 3675);
FORCEADD UNIVERSAL_GND..1
(-175 3575);
FORCEPROP 3 LASTPIN (-175 3625) SIG_NAME GND\g
J 0
(-165 3635);
DISPLAY 0.659574 (-165 3635);
PAINT MONO (-165 3635);
DISPLAY INVISIBLE (-165 3635);
FORCEPROP 2 LAST CDS_LIB pure_quanta_power
J 0
(-175 3575);
PAINT MONO (-175 3575);
DISPLAY INVISIBLE (-175 3575);
FORCEPROP 1 LAST HDL_POWER GND
J 1
(-150 3500);
DISPLAY 0.872340 (-150 3500);
PAINT GREEN (-150 3500);
DISPLAY INVISIBLE (-150 3500);
FORCEPROP 1 LAST PATH I57
J 0
(-100 3575);
DISPLAY 0.872340 (-100 3575);
PAINT AQUA (-100 3575);
DISPLAY INVISIBLE (-100 3575);
FORCEADD UNIVERSAL_GND..1
(-2075 4200);
FORCEPROP 3 LASTPIN (-2075 4250) SIG_NAME GND\g
J 0
(-2065 4260);
DISPLAY 0.659574 (-2065 4260);
PAINT MONO (-2065 4260);
DISPLAY INVISIBLE (-2065 4260);
FORCEPROP 2 LAST CDS_LIB pure_quanta_power
J 0
(-2075 4200);
PAINT MONO (-2075 4200);
DISPLAY INVISIBLE (-2075 4200);
FORCEPROP 1 LAST HDL_POWER GND
J 1
(-2050 4125);
DISPLAY 0.872340 (-2050 4125);
PAINT GREEN (-2050 4125);
DISPLAY INVISIBLE (-2050 4125);
FORCEPROP 1 LAST PATH I58
J 0
(-2000 4200);
DISPLAY 0.872340 (-2000 4200);
PAINT AQUA (-2000 4200);
DISPLAY INVISIBLE (-2000 4200);
FORCEADD Q_CAP..1
R 2
(-2075 4425);
FORCEPROP 1 LAST LOCATION C639
J 2
(-2125 4525);
DISPLAY 0.978723 (-2125 4525);
FORCEPROP 2 LAST $SEC 1
J 0
(-2125 4625);
DISPLAY 0.680851 (-2125 4625);
PAINT MONO (-2125 4625);
DISPLAY INVISIBLE (-2125 4625);
FORCEPROP 2 LAST CDS_SEC 1
J 0
(-2125 4625);
DISPLAY 1.021277 (-2125 4625);
DISPLAY INVISIBLE (-2125 4625);
FORCEPROP 1 LASTPIN (-2075 4525) $PN 1
J 2
(-2085 4505);
DISPLAY 0.787234 (-2085 4505);
FORCEPROP 1 LASTPIN (-2075 4325) $PN 2
J 2
(-2085 4305);
DISPLAY 0.787234 (-2085 4305);
FORCEPROP 1 LAST VALUE 0.1UF
J 2
(-2125 4475);
DISPLAY 0.510638 (-2125 4475);
FORCEPROP 1 LAST VOLTAGE 25V
J 2
(-2125 4425);
DISPLAY 0.510638 (-2125 4425);
FORCEPROP 1 LAST TOLERANCE 10%
J 2
(-2125 4375);
DISPLAY 0.510638 (-2125 4375);
FORCEPROP 1 LAST MATERIAL X7R
J 2
(-2125 4325);
DISPLAY 0.510638 (-2125 4325);
FORCEPROP 1 LAST PACK_TYPE 0402
J 2
(-2125 4225);
DISPLAY 0.510638 (-2125 4225);
FORCEPROP 2 LAST CDS_LIB pure_quanta
J 0
(-2075 4425);
PAINT MONO (-2075 4425);
DISPLAY INVISIBLE (-2075 4425);
FORCEPROP 1 LAST PATH I59
J 2
(-2125 4575);
DISPLAY 0.978723 (-2125 4575);
PAINT WHITE (-2125 4575);
DISPLAY INVISIBLE (-2125 4575);
FORCEPROP 1 LAST PART_NUMBER CH4104K1B00
J 2
(-2125 4275);
DISPLAY 0.510638 (-2125 4275);
DISPLAY INVISIBLE (-2125 4275);
FORCEADD OFFPAGE..1
(-2750 4050);
FORCEPROP 2 LAST $XR1 82 
J 0
(-3122 4050);
DISPLAY 0.638298 (-3122 4050);
PAINT MONO (-3122 4050);
FORCEPROP 2 LAST $XR0 131 
J 0
(-3032 4050);
DISPLAY 0.638298 (-3032 4050);
PAINT MONO (-3032 4050);
FORCEPROP 2 LAST CDS_LIB standard
J 0
(-2750 4050);
PAINT MONO (-2750 4050);
DISPLAY INVISIBLE (-2750 4050);
FORCEPROP 1 LAST OFFPAGE TRUE
J 0
(-2425 3925);
DISPLAY 0.872340 (-2425 3925);
PAINT GREEN (-2425 3925);
DISPLAY INVISIBLE (-2425 3925);
FORCEPROP 1 LAST COMMENT_BODY TRUE
J 0
(-2625 3950);
DISPLAY 0.872340 (-2625 3950);
PAINT GREEN (-2625 3950);
DISPLAY INVISIBLE (-2625 3950);
FORCEPROP 2 LAST PATH I61
J 0
(-2700 4125);
DISPLAY 1.021277 (-2700 4125);
DISPLAY INVISIBLE (-2700 4125);
FORCEADD OFFPAGE..4
(2600 5025);
FORCEPROP 2 LAST $XR2 138 
J 0
(3026 5025);
DISPLAY 0.638298 (3026 5025);
PAINT MONO (3026 5025);
FORCEPROP 2 LAST $XR1 150 
J 0
(2906 5025);
DISPLAY 0.638298 (2906 5025);
PAINT MONO (2906 5025);
FORCEPROP 2 LAST $XR0 132 
J 0
(2786 5025);
DISPLAY 0.638298 (2786 5025);
PAINT MONO (2786 5025);
FORCEPROP 2 LAST CDS_LIB standard
J 0
(2600 5025);
PAINT MONO (2600 5025);
DISPLAY INVISIBLE (2600 5025);
FORCEPROP 1 LAST OFFPAGE TRUE
J 0
(2925 4900);
DISPLAY 0.872340 (2925 4900);
PAINT GREEN (2925 4900);
DISPLAY INVISIBLE (2925 4900);
FORCEPROP 1 LAST COMMENT_BODY TRUE
J 0
(2575 4925);
DISPLAY 0.872340 (2575 4925);
PAINT GREEN (2575 4925);
DISPLAY INVISIBLE (2575 4925);
FORCEPROP 2 LAST PATH I62
J 0
(2775 5100);
DISPLAY 1.021277 (2775 5100);
DISPLAY INVISIBLE (2775 5100);
FORCEADD OFFPAGE..2
(2375 6750);
FORCEPROP 2 LAST $XR2 150 
J 0
(2564 6714);
DISPLAY 0.638298 (2564 6714);
PAINT MONO (2564 6714);
FORCEPROP 2 LAST $XR1 138 
J 0
(2684 6750);
DISPLAY 0.638298 (2684 6750);
PAINT MONO (2684 6750);
FORCEPROP 2 LAST $XR0 132 
J 0
(2564 6750);
DISPLAY 0.638298 (2564 6750);
PAINT MONO (2564 6750);
FORCEPROP 2 LAST CDS_LIB standard
J 0
(2375 6750);
PAINT MONO (2375 6750);
DISPLAY INVISIBLE (2375 6750);
FORCEPROP 1 LAST OFFPAGE TRUE
J 0
(2700 6625);
DISPLAY 0.872340 (2700 6625);
PAINT GREEN (2700 6625);
DISPLAY INVISIBLE (2700 6625);
FORCEPROP 1 LAST COMMENT_BODY TRUE
J 0
(2330 6655);
DISPLAY 0.872340 (2330 6655);
PAINT GREEN (2330 6655);
DISPLAY INVISIBLE (2330 6655);
FORCEPROP 2 LAST PATH I64
J 0
(2550 6825);
DISPLAY 1.021277 (2550 6825);
DISPLAY INVISIBLE (2550 6825);
FORCEADD OFFPAGE..2
(2375 6600);
FORCEPROP 2 LAST $XR2 150 
J 0
(2804 6600);
DISPLAY 0.638298 (2804 6600);
PAINT MONO (2804 6600);
FORCEPROP 2 LAST $XR1 138 
J 0
(2684 6600);
DISPLAY 0.638298 (2684 6600);
PAINT MONO (2684 6600);
FORCEPROP 2 LAST $XR0 132 
J 0
(2564 6600);
DISPLAY 0.638298 (2564 6600);
PAINT MONO (2564 6600);
FORCEPROP 2 LAST CDS_LIB standard
J 0
(2375 6600);
PAINT MONO (2375 6600);
DISPLAY INVISIBLE (2375 6600);
FORCEPROP 1 LAST OFFPAGE TRUE
J 0
(2700 6475);
DISPLAY 0.872340 (2700 6475);
PAINT GREEN (2700 6475);
DISPLAY INVISIBLE (2700 6475);
FORCEPROP 1 LAST COMMENT_BODY TRUE
J 0
(2330 6505);
DISPLAY 0.872340 (2330 6505);
PAINT GREEN (2330 6505);
DISPLAY INVISIBLE (2330 6505);
FORCEPROP 2 LAST PATH I65
J 0
(2550 6675);
DISPLAY 1.021277 (2550 6675);
DISPLAY INVISIBLE (2550 6675);
FORCEADD OFFPAGE..2
(2375 6450);
FORCEPROP 2 LAST $XR2 150 
J 0
(2804 6450);
DISPLAY 0.638298 (2804 6450);
PAINT MONO (2804 6450);
FORCEPROP 2 LAST $XR1 138 
J 0
(2684 6450);
DISPLAY 0.638298 (2684 6450);
PAINT MONO (2684 6450);
FORCEPROP 2 LAST $XR0 132 
J 0
(2564 6450);
DISPLAY 0.638298 (2564 6450);
PAINT MONO (2564 6450);
FORCEPROP 2 LAST CDS_LIB standard
J 0
(2375 6450);
PAINT MONO (2375 6450);
DISPLAY INVISIBLE (2375 6450);
FORCEPROP 1 LAST OFFPAGE TRUE
J 0
(2700 6325);
DISPLAY 0.872340 (2700 6325);
PAINT GREEN (2700 6325);
DISPLAY INVISIBLE (2700 6325);
FORCEPROP 1 LAST COMMENT_BODY TRUE
J 0
(2330 6355);
DISPLAY 0.872340 (2330 6355);
PAINT GREEN (2330 6355);
DISPLAY INVISIBLE (2330 6355);
FORCEPROP 2 LAST PATH I66
J 0
(2550 6525);
DISPLAY 1.021277 (2550 6525);
DISPLAY INVISIBLE (2550 6525);
FORCEADD OFFPAGE..4
(2600 5175);
FORCEPROP 2 LAST $XR2 138 
J 0
(3026 5175);
DISPLAY 0.638298 (3026 5175);
PAINT MONO (3026 5175);
FORCEPROP 2 LAST $XR1 150 
J 0
(2906 5175);
DISPLAY 0.638298 (2906 5175);
PAINT MONO (2906 5175);
FORCEPROP 2 LAST $XR0 132 
J 0
(2786 5175);
DISPLAY 0.638298 (2786 5175);
PAINT MONO (2786 5175);
FORCEPROP 2 LAST CDS_LIB standard
J 0
(2600 5175);
PAINT MONO (2600 5175);
DISPLAY INVISIBLE (2600 5175);
FORCEPROP 1 LAST OFFPAGE TRUE
J 0
(2925 5050);
DISPLAY 0.872340 (2925 5050);
PAINT GREEN (2925 5050);
DISPLAY INVISIBLE (2925 5050);
FORCEPROP 1 LAST COMMENT_BODY TRUE
J 0
(2575 5075);
DISPLAY 0.872340 (2575 5075);
PAINT GREEN (2575 5075);
DISPLAY INVISIBLE (2575 5075);
FORCEPROP 2 LAST PATH I78
J 0
(2775 5250);
DISPLAY 1.021277 (2775 5250);
DISPLAY INVISIBLE (2775 5250);
FORCEADD OFFPAGE..4
(2600 5325);
FORCEPROP 2 LAST $XR2 138 
J 0
(3026 5325);
DISPLAY 0.638298 (3026 5325);
PAINT MONO (3026 5325);
FORCEPROP 2 LAST $XR1 150 
J 0
(2906 5325);
DISPLAY 0.638298 (2906 5325);
PAINT MONO (2906 5325);
FORCEPROP 2 LAST $XR0 132 
J 0
(2786 5325);
DISPLAY 0.638298 (2786 5325);
PAINT MONO (2786 5325);
FORCEPROP 2 LAST CDS_LIB standard
J 0
(2600 5325);
PAINT MONO (2600 5325);
DISPLAY INVISIBLE (2600 5325);
FORCEPROP 1 LAST OFFPAGE TRUE
J 0
(2925 5200);
DISPLAY 0.872340 (2925 5200);
PAINT GREEN (2925 5200);
DISPLAY INVISIBLE (2925 5200);
FORCEPROP 1 LAST COMMENT_BODY TRUE
J 0
(2575 5225);
DISPLAY 0.872340 (2575 5225);
PAINT GREEN (2575 5225);
DISPLAY INVISIBLE (2575 5225);
FORCEPROP 2 LAST PATH I79
J 0
(2775 5400);
DISPLAY 1.021277 (2775 5400);
DISPLAY INVISIBLE (2775 5400);
FORCEADD OFFPAGE..4
(3825 5475);
FORCEPROP 2 LAST $XR0 143 
J 0
(4011 5475);
DISPLAY 0.638298 (4011 5475);
PAINT MONO (4011 5475);
FORCEPROP 2 LAST CDS_LIB standard
J 0
(3825 5475);
PAINT MONO (3825 5475);
DISPLAY INVISIBLE (3825 5475);
FORCEPROP 1 LAST OFFPAGE TRUE
J 0
(4150 5350);
DISPLAY 0.872340 (4150 5350);
PAINT GREEN (4150 5350);
DISPLAY INVISIBLE (4150 5350);
FORCEPROP 1 LAST COMMENT_BODY TRUE
J 0
(3800 5375);
DISPLAY 0.872340 (3800 5375);
PAINT GREEN (3800 5375);
DISPLAY INVISIBLE (3800 5375);
FORCEPROP 2 LAST PATH I80
J 0
(4000 5550);
DISPLAY 1.021277 (4000 5550);
DISPLAY INVISIBLE (4000 5550);
FORCEADD OFFPAGE..2
(3875 6900);
FORCEPROP 2 LAST $XR0 143 
J 0
(4064 6900);
DISPLAY 0.638298 (4064 6900);
PAINT MONO (4064 6900);
FORCEPROP 2 LAST CDS_LIB standard
J 0
(3875 6900);
PAINT MONO (3875 6900);
DISPLAY INVISIBLE (3875 6900);
FORCEPROP 1 LAST OFFPAGE TRUE
J 0
(4200 6775);
DISPLAY 0.872340 (4200 6775);
PAINT GREEN (4200 6775);
DISPLAY INVISIBLE (4200 6775);
FORCEPROP 1 LAST COMMENT_BODY TRUE
J 0
(3830 6805);
DISPLAY 0.872340 (3830 6805);
PAINT GREEN (3830 6805);
DISPLAY INVISIBLE (3830 6805);
FORCEPROP 2 LAST PATH I81
J 0
(4050 6975);
DISPLAY 1.021277 (4050 6975);
DISPLAY INVISIBLE (4050 6975);
FORCEADD Q_RES..1
(3050 6900);
FORCEPROP 1 LAST LOCATION R1290
J 0
(2750 6900);
DISPLAY 0.702128 (2750 6900);
PAINT YELLOW (2750 6900);
FORCEPROP 0 LAST $SEC 1
J 0
(3125 6950);
DISPLAY INVISIBLE (3125 6950);
FORCEPROP 0 LAST CDS_SEC 1
J 0
(3125 6950);
DISPLAY INVISIBLE (3125 6950);
FORCEPROP 1 LASTPIN (2950 6900) $PN 1
J 0
(2962 6912);
DISPLAY 0.808511 (2962 6912);
PAINT WHITE (2962 6912);
DISPLAY INVISIBLE (2962 6912);
FORCEPROP 1 LASTPIN (3150 6900) $PN 2
J 0
(3112 6912);
DISPLAY 0.808511 (3112 6912);
PAINT WHITE (3112 6912);
DISPLAY INVISIBLE (3112 6912);
FORCEPROP 1 LAST VALUE 22
J 2
(3000 6925);
DISPLAY 0.510638 (3000 6925);
PAINT SKYBLUE (3000 6925);
FORCEPROP 1 LAST WATTAGE 1/16W
J 2
(3050 7000);
DISPLAY 0.510638 (3050 7000);
PAINT SKYBLUE (3050 7000);
FORCEPROP 1 LAST PACK_TYPE 0402LF
J 0
(3075 7000);
DISPLAY 0.510638 (3075 7000);
PAINT SKYBLUE (3075 7000);
FORCEPROP 1 LAST MATERIAL EMPTY
J 0
(3050 6925);
DISPLAY 0.510638 (3050 6925);
PAINT RED (3050 6925);
FORCEPROP 1 LAST TOLERANCE 1%
J 0
(3050 6800);
DISPLAY 0.510638 (3050 6800);
PAINT SKYBLUE (3050 6800);
DISPLAY INVISIBLE (3050 6800);
FORCEPROP 2 LAST CDS_LIB pure_quanta
J 0
(3050 6900);
DISPLAY INVISIBLE (3050 6900);
FORCEPROP 1 LAST PATH I98
J 0
(3000 7050);
DISPLAY 0.978723 (3000 7050);
PAINT WHITE (3000 7050);
DISPLAY INVISIBLE (3000 7050);
FORCEPROP 1 LAST PART_NUMBER CS02202FB02
J 0
(2950 7050);
DISPLAY 0.510638 (2950 7050);
PAINT WHITE (2950 7050);
DISPLAY INVISIBLE (2950 7050);
FORCEADD Q_RES..1
(1450 6750);
FORCEPROP 1 LAST LOCATION R59
J 0
(1150 6750);
DISPLAY 0.702128 (1150 6750);
PAINT YELLOW (1150 6750);
FORCEPROP 0 LAST $SEC 1
J 0
(1525 6800);
DISPLAY INVISIBLE (1525 6800);
FORCEPROP 0 LAST CDS_SEC 1
J 0
(1525 6800);
DISPLAY INVISIBLE (1525 6800);
FORCEPROP 1 LASTPIN (1350 6750) $PN 1
J 0
(1362 6762);
DISPLAY 0.808511 (1362 6762);
PAINT WHITE (1362 6762);
DISPLAY INVISIBLE (1362 6762);
FORCEPROP 1 LASTPIN (1550 6750) $PN 2
J 0
(1512 6762);
DISPLAY 0.808511 (1512 6762);
PAINT WHITE (1512 6762);
DISPLAY INVISIBLE (1512 6762);
FORCEPROP 1 LAST MATERIAL CHIP
J 0
(1525 6775);
DISPLAY 0.510638 (1525 6775);
PAINT SKYBLUE (1525 6775);
FORCEPROP 1 LAST VALUE 22
J 2
(1400 6775);
DISPLAY 0.510638 (1400 6775);
PAINT SKYBLUE (1400 6775);
FORCEPROP 2 LAST CDS_LIB pure_quanta
J 0
(1450 6750);
DISPLAY INVISIBLE (1450 6750);
FORCEPROP 1 LAST PACK_TYPE 0402LF
J 0
(1700 6600);
DISPLAY 0.510638 (1700 6600);
PAINT SKYBLUE (1700 6600);
DISPLAY INVISIBLE (1700 6600);
FORCEPROP 1 LAST TOLERANCE 1%
J 0
(1450 6650);
DISPLAY 0.510638 (1450 6650);
PAINT SKYBLUE (1450 6650);
DISPLAY INVISIBLE (1450 6650);
FORCEPROP 1 LAST WATTAGE 1/16W
J 2
(1425 6600);
DISPLAY 0.510638 (1425 6600);
PAINT SKYBLUE (1425 6600);
DISPLAY INVISIBLE (1425 6600);
FORCEPROP 1 LAST PATH I99
J 0
(1400 6900);
DISPLAY 0.978723 (1400 6900);
PAINT WHITE (1400 6900);
DISPLAY INVISIBLE (1400 6900);
FORCEPROP 1 LAST PART_NUMBER CS02202FB02
J 0
(1400 6850);
DISPLAY 0.510638 (1400 6850);
PAINT WHITE (1400 6850);
DISPLAY INVISIBLE (1400 6850);
FORCEADD DNS..2
(-500 3475);
PAINT RED (-500 3475);
FORCEPROP 2 LAST CDS_LIB mstr_misc
J 0
(-500 3475);
DISPLAY INVISIBLE (-500 3475);
FORCEPROP 1 LAST COMMENT_BODY TRUE
R 1
J 0
(-425 3250);
DISPLAY 0.872340 (-425 3250);
PAINT GREEN (-425 3250);
DISPLAY INVISIBLE (-425 3250);
FORCEADD QUANTA_TITLE_BLOCK_C..1
(4175 1175);
FORCEPROP 0 LAST CDS_CON_LAST_MODIFIED Thu Sep 14 16:12:25 2023
J 0
(2290 1190);
PAINT MONO (2290 1190);
DISPLAY INVISIBLE (2290 1190);
FORCEPROP 2 LAST CUSTOM_TXT_CDS <XR_PAGE_TITLE>
J 0
(-3715 6425);
DISPLAY 0.638298 (-3715 6425);
PAINT PINK (-3715 6425);
DISPLAY INVISIBLE (-3715 6425);
FORCEPROP 2 LAST CUSTOM_TXT_CDS <CON_LAST_MODIFIED>
J 0
(2290 1190);
DISPLAY 0.978723 (2290 1190);
FORCEPROP 2 LAST CUSTOM_TXT_CDS <Q_PROJ>
J 0
(1793 1277);
DISPLAY 1.212766 (1793 1277);
FORCEPROP 2 LAST CUSTOM_TXT_CDS <NAME_2>
J 0
(1000 1225);
FORCEPROP 2 LAST CUSTOM_TXT_CDS <NAME_1>
J 0
(1000 1350);
FORCEPROP 2 LAST CUSTOM_TXT_CDS <Q_NUMBER>
J 0
(2772 1278);
DISPLAY 1.212766 (2772 1278);
FORCEPROP 2 LAST CUSTOM_TXT_CDS <Q_REV>
J 0
(3991 1278);
DISPLAY 1.212766 (3991 1278);
FORCEPROP 1 LAST CUSTOM_TXT_CDS <CON_PAGE_NUM> OF <CON_TOTAL_PAGES>
J 0
(3729 1193);
DISPLAY 0.978723 (3729 1193);
FORCEPROP 1 LAST Q_TITLE PCIE - SFF OCP3.0 (2/3)
J 0
(-5191 1201);
DISPLAY 1.957447 (-5191 1201);
PAINT GREEN (-5191 1201);
FORCEPROP 2 LAST PAGE_BORDER TRUE
J 0
(-3715 6425);
DISPLAY 0.638298 (-3715 6425);
PAINT PINK (-3715 6425);
DISPLAY INVISIBLE (-3715 6425);
FORCEPROP 1 LAST CDS_LMAN_SYM_OUTLINE -9475,6775,100,-125
J 0
(4175 1175);
DISPLAY 0.468085 (4175 1175);
PAINT GREEN (4175 1175);
DISPLAY INVISIBLE (4175 1175);
FORCEPROP 2 LAST CDS_LIB pure_quanta
J 0
(4175 1175);
PAINT MONO (4175 1175);
DISPLAY INVISIBLE (4175 1175);
FORCEPROP 2 LAST CDS_XR_PAGE_TITLE CR-132 : @T6G_MB_LIB.T6G(SCH_1):PAGE132
J 0
(-3715 6425);
DISPLAY 0.638298 (-3715 6425);
PAINT PINK (-3715 6425);
DISPLAY INVISIBLE (-3715 6425);
FORCEPROP 1 LAST Q_DEPT BU9
J 1
(412 1224);
DISPLAY 1.957447 (412 1224);
PAINT GREEN (412 1224);
DISPLAY INVISIBLE (412 1224);
FORCEPROP 1 LAST COMMENT_BODY TRUE
J 0
(4187 1162);
DISPLAY 0.978723 (4187 1162);
PAINT GREEN (4187 1162);
DISPLAY INVISIBLE (4187 1162);
FORCEADD DNS..2
(3075 6900);
PAINT RED (3075 6900);
FORCEPROP 2 LAST CDS_LIB mstr_misc
J 0
(3075 6900);
DISPLAY INVISIBLE (3075 6900);
FORCEPROP 1 LAST COMMENT_BODY TRUE
R 1
J 0
(3150 6675);
DISPLAY 0.872340 (3150 6675);
PAINT GREEN (3150 6675);
DISPLAY INVISIBLE (3150 6675);
WIRE 16 -1 (-2350 2600)(-2350 2525);
WIRE 16 -1 (-975 5700)(-975 5625);
WIRE 16 -1 (-1125 1950)(-1125 1875);
WIRE 16 -1 (-1650 3750)(-1650 3675);
WIRE 16 -1 (-1975 2025)(-1975 1950);
WIRE 16 -1 (-775 4975)(-625 4975);
FORCEPROP 0 LAST CDS_PHYS_NET_NAME GND
J 0
(-700 5022);
PAINT MONO (-700 5022);
DISPLAY INVISIBLE (-700 5022);
FORCEPROP 0 LAST VOLTAGE 0
J 0
(-700 4975);
PAINT MONO (-700 4975);
DISPLAY INVISIBLE (-700 4975);
WIRE 16 -1 (-775 4975)(-775 4900);
WIRE 16 -1 (-775 6400)(-625 6400);
FORCEPROP 0 LAST CDS_PHYS_NET_NAME GND
J 0
(-700 6447);
PAINT MONO (-700 6447);
DISPLAY INVISIBLE (-700 6447);
FORCEPROP 0 LAST VOLTAGE 0
J 0
(-700 6400);
PAINT MONO (-700 6400);
DISPLAY INVISIBLE (-700 6400);
WIRE 16 -1 (-775 6400)(-775 6325);
WIRE 16 -1 (-975 7125)(-975 7050);
WIRE 16 -1 (-175 3700)(-175 3625);
WIRE 16 -1 (-2075 4325)(-2075 4250);
WIRE 16 -1 (-3450 2225)(-4250 2225);
FORCEPROP 0 LAST CDS_PHYS_NET_NAME OCP_V3_2_AUX_PWR_EN
J 0
(-3885 2267);
PAINT MONO (-3885 2267);
DISPLAY INVISIBLE (-3885 2267);
FORCEPROP 2 LAST SIG_NAME OCP_SFF_AUX_PWR_EN
J 0
(-4235 2235);
DISPLAY 0.680851 (-4235 2235);
PAINT SKYBLUE (-4235 2235);
WIRE 16 -1 (-3550 3950)(-4450 3950);
FORCEPROP 0 LAST CDS_PHYS_NET_NAME OCP_SFF_RBT_ARB_IN
J 0
(-4085 3992);
PAINT MONO (-4085 3992);
DISPLAY INVISIBLE (-4085 3992);
FORCEPROP 2 LAST SIG_NAME OCP_SFF_AUX_PWR_EN
J 0
(-4360 3960);
DISPLAY 0.680851 (-4360 3960);
PAINT SKYBLUE (-4360 3960);
WIRE 16 -1 (-3175 2325)(-2225 2325);
FORCEPROP 0 LAST CDS_PHYS_NET_NAME RST_SMB_SWITCH_N
J 0
(-2810 2367);
PAINT MONO (-2810 2367);
DISPLAY INVISIBLE (-2810 2367);
FORCEPROP 2 LAST SIG_NAME RST_SMB_SWITCH_N
J 0
(-3035 2335);
DISPLAY 0.680851 (-3035 2335);
PAINT WHITE (-3035 2335);
WIRE 16 -1 (-2225 2225)(-3250 2225);
FORCEPROP 0 LAST CDS_PHYS_NET_NAME OCP_V3_2_AUX_PWR_EN_R4
J 0
(-2885 2267);
PAINT MONO (-2885 2267);
DISPLAY INVISIBLE (-2885 2267);
FORCEPROP 2 LAST SIG_NAME OCP_SFF_AUX_PWR_EN_R2
J 0
(-3035 2235);
DISPLAY 0.680851 (-3035 2235);
PAINT SKYBLUE (-3035 2235);
FORCEPROP 2 LASTPROP $XRERR UNIQUE?
J 0
(-3275 2235);
DISPLAY 0.638298 (-3275 2235);
PAINT MONO (-3275 2235);
DISPLAY INVISIBLE (-3275 2235);
WIRE 16 -1 (50 2275)(-700 2275);
FORCEPROP 2 LAST SIG_NAME RST_SMB_OCP_SFF_N
J 0
(-435 2285);
DISPLAY 0.553191 (-435 2285);
PAINT WHITE (-435 2285);
WIRE 16 -1 (-1725 2275)(-1125 2275);
FORCEPROP 2 LAST SIG_NAME RST_HP_OCP_SFF_R_N
J 0
(-1660 2285);
DISPLAY 0.553191 (-1660 2285);
PAINT WHITE (-1660 2285);
FORCEPROP 2 LASTPROP $XRERR UNIQUE?
J 0
(-1900 2285);
DISPLAY 0.638298 (-1900 2285);
PAINT MONO (-1900 2285);
DISPLAY INVISIBLE (-1900 2285);
WIRE 16 -1 (-900 2275)(-1125 2275);
WIRE 16 -1 (-1125 2150)(-1125 2275);
WIRE 16 -1 (-1975 2875)(-1975 2525);
WIRE 16 -1 (-1975 2875)(-2350 2875);
WIRE 16 -1 (-2350 2875)(-2350 2950);
WIRE 16 -1 (-2350 2875)(-2350 2800);
WIRE 16 -1 (-1750 3475)(-625 3475);
FORCEPROP 2 LAST SIG_NAME FM_NCSI_OCP_SFF_R_OE
J 0
(-1585 3485);
DISPLAY 0.553191 (-1585 3485);
PAINT WHITE (-1585 3485);
WIRE 16 -1 (-3350 3950)(-1900 3950);
FORCEPROP 2 LAST SIG_NAME OCP_SFF_AUX_PWR_EN_R1
J 0
(-2885 3960);
DISPLAY 0.680851 (-2885 3960);
PAINT SKYBLUE (-2885 3960);
FORCEPROP 2 LASTPROP $XRERR UNIQUE?
J 0
(-3125 3960);
DISPLAY 0.638298 (-3125 3960);
PAINT MONO (-3125 3960);
DISPLAY INVISIBLE (-3125 3960);
WIRE 16 -1 (-2700 4050)(-1900 4050);
FORCEPROP 0 LAST CDS_PHYS_NET_NAME OCP_SFF_RBT_ARB_IN
J 0
(-2335 4092);
PAINT MONO (-2335 4092);
DISPLAY INVISIBLE (-2335 4092);
FORCEPROP 2 LAST SIG_NAME FM_OCP_SFF_PWR_GOOD
J 0
(-2560 4060);
DISPLAY 0.680851 (-2560 4060);
PAINT SKYBLUE (-2560 4060);
WIRE 16 -1 (-1650 4250)(-1650 4550);
WIRE 16 -1 (-1650 4550)(-2075 4550);
WIRE 16 -1 (-2075 4550)(-2075 4525);
WIRE 16 -1 (-2075 4550)(-2075 4600);
WIRE 16 -1 (-1400 4000)(-525 4000);
FORCEPROP 2 LAST SIG_NAME FB_BMC_ISOLATE_R1
J 0
(-1235 4010);
DISPLAY 0.553191 (-1235 4010);
PAINT SKYBLUE (-1235 4010);
FORCEPROP 2 LASTPROP $XRERR UNIQUE?
J 0
(-1475 4010);
DISPLAY 0.638298 (-1475 4010);
PAINT MONO (-1475 4010);
DISPLAY INVISIBLE (-1475 4010);
WIRE 16 -1 (400 4975)(400 4000);
WIRE 16 -1 (400 5125)(400 4975);
WIRE 16 -1 (175 4975)(400 4975);
WIRE 16 -1 (400 4000)(550 4000);
WIRE 16 -1 (400 4000)(400 3475);
WIRE 16 -1 (-175 4000)(400 4000);
FORCEPROP 2 LAST SIG_NAME FB_BMC_ISOLATE
J 0
(15 4010);
DISPLAY 0.553191 (15 4010);
PAINT WHITE (15 4010);
WIRE 16 -1 (-175 3900)(-175 4000);
WIRE 16 -1 (-325 4000)(-175 4000);
WIRE 16 -1 (400 3475)(-425 3475);
WIRE 16 -1 (400 5275)(400 5125);
WIRE 16 -1 (175 5125)(400 5125);
WIRE 16 -1 (400 5425)(400 5275);
WIRE 16 -1 (175 5275)(400 5275);
WIRE 16 -1 (400 6400)(400 5425);
WIRE 16 -1 (175 5425)(400 5425);
WIRE 16 -1 (400 6550)(400 6400);
WIRE 16 -1 (175 6400)(400 6400);
WIRE 16 -1 (400 6700)(400 6550);
WIRE 16 -1 (175 6550)(400 6550);
WIRE 16 -1 (400 6850)(400 6700);
WIRE 16 -1 (175 6700)(400 6700);
WIRE 16 -1 (175 6850)(400 6850);
WIRE 16 -1 (2125 2000)(2125 1925);
WIRE 16 -1 (2125 1925)(2375 1925);
WIRE 16 -1 (1875 1925)(2125 1925);
WIRE 16 -1 (1875 2000)(1875 1925);
WIRE 16 -1 (2375 2000)(2375 1925);
WIRE 16 -1 (2375 1925)(2375 1875);
WIRE 16 -1 (3125 4475)(3625 4475);
WIRE 16 -1 (3625 4475)(3625 4325);
WIRE 16 -1 (3625 4325)(3625 4175);
WIRE 16 -1 (3125 4325)(3625 4325);
WIRE 16 -1 (3125 4175)(3625 4175);
WIRE 16 -1 (3625 4175)(3625 4025);
WIRE 16 -1 (3625 4025)(3625 3875);
WIRE 16 -1 (3125 4025)(3625 4025);
WIRE 16 -1 (3625 3875)(3625 3725);
WIRE 16 -1 (3125 3875)(3625 3875);
WIRE 16 -1 (3625 3725)(3625 3550);
WIRE 16 -1 (3125 3725)(3625 3725);
WIRE 16 -1 (3125 3550)(3625 3550);
WIRE 16 -1 (3625 3550)(3625 3375);
WIRE 16 -1 (-775 5525)(-775 5975);
FORCEPROP 0 LAST CDS_PHYS_NET_NAME P3V3_AUX
J 0
(-775 5797);
PAINT MONO (-775 5797);
DISPLAY INVISIBLE (-775 5797);
FORCEPROP 0 LAST VOLTAGE 3.3
J 0
(-775 5750);
PAINT MONO (-775 5750);
DISPLAY INVISIBLE (-775 5750);
FORCEPROP 0 LAST $PHYS_NET_NAME P3V3_AUX
J 0
(-775 5844);
PAINT MONO (-775 5844);
DISPLAY INVISIBLE (-775 5844);
WIRE 16 -1 (-775 5525)(-625 5525);
FORCEPROP 0 LAST CDS_PHYS_NET_NAME P3V3_AUX
J 0
(-700 5572);
PAINT MONO (-700 5572);
DISPLAY INVISIBLE (-700 5572);
FORCEPROP 0 LAST VOLTAGE 3.3
J 0
(-700 5525);
PAINT MONO (-700 5525);
DISPLAY INVISIBLE (-700 5525);
FORCEPROP 0 LAST $PHYS_NET_NAME P3V3_AUX
J 0
(-700 5619);
PAINT MONO (-700 5619);
DISPLAY INVISIBLE (-700 5619);
WIRE 16 -1 (-975 5975)(-775 5975);
WIRE 16 -1 (-775 5975)(-775 6075);
WIRE 16 -1 (-975 5975)(-975 5900);
WIRE 16 -1 (-775 6950)(-775 7400);
FORCEPROP 0 LAST CDS_PHYS_NET_NAME P3V3_AUX
J 0
(-775 7222);
PAINT MONO (-775 7222);
DISPLAY INVISIBLE (-775 7222);
FORCEPROP 0 LAST VOLTAGE 3.3
J 0
(-775 7175);
PAINT MONO (-775 7175);
DISPLAY INVISIBLE (-775 7175);
FORCEPROP 0 LAST $PHYS_NET_NAME P3V3_AUX
J 0
(-775 7269);
PAINT MONO (-775 7269);
DISPLAY INVISIBLE (-775 7269);
WIRE 16 -1 (-775 6950)(-625 6950);
FORCEPROP 0 LAST CDS_PHYS_NET_NAME P3V3_AUX
J 0
(-700 6997);
PAINT MONO (-700 6997);
DISPLAY INVISIBLE (-700 6997);
FORCEPROP 0 LAST VOLTAGE 3.3
J 0
(-700 6950);
PAINT MONO (-700 6950);
DISPLAY INVISIBLE (-700 6950);
FORCEPROP 0 LAST $PHYS_NET_NAME P3V3_AUX
J 0
(-700 7044);
PAINT MONO (-700 7044);
DISPLAY INVISIBLE (-700 7044);
WIRE 16 -1 (-975 7400)(-775 7400);
WIRE 16 -1 (-775 7400)(-775 7500);
WIRE 16 -1 (-975 7400)(-975 7325);
WIRE 16 -1 (2900 6900)(2950 6900);
WIRE 16 -1 (2900 6825)(2900 6900);
WIRE 16 -1 (2900 6900)(175 6900);
FORCEPROP 0 LAST CDS_PHYS_NET_NAME OCP_SFF_RBT_ARB_IN
J 0
(540 6942);
PAINT MONO (540 6942);
DISPLAY INVISIBLE (540 6942);
FORCEPROP 2 LAST SIG_NAME OCP_SFF_RBT_ARB_IN_R
J 0
(465 6910);
DISPLAY 0.680851 (465 6910);
PAINT WHITE (465 6910);
FORCEPROP 2 LASTPROP $XRERR UNIQUE?
J 0
(225 6910);
DISPLAY 0.638298 (225 6910);
PAINT MONO (225 6910);
DISPLAY INVISIBLE (225 6910);
WIRE 16 -1 (3825 6900)(3150 6900);
FORCEPROP 2 LAST SIG_NAME OCP_SFF_RBT_ARB_IN
J 0
(3215 6910);
DISPLAY 0.680851 (3215 6910);
PAINT WHITE (3215 6910);
WIRE 16 -1 (2325 6600)(1550 6600);
FORCEPROP 2 LAST SIG_NAME RMII_OCP_BMC_RXD_0
J 0
(1690 6610);
DISPLAY 0.680851 (1690 6610);
PAINT WHITE (1690 6610);
WIRE 16 -1 (2325 6750)(1550 6750);
FORCEPROP 2 LAST SIG_NAME RMII_OCP_BMC_CRSDV
J 0
(1690 6760);
DISPLAY 0.680851 (1690 6760);
PAINT WHITE (1690 6760);
WIRE 16 -1 (2325 6450)(1550 6450);
FORCEPROP 2 LAST SIG_NAME RMII_OCP_BMC_RXD_1
J 0
(1690 6460);
DISPLAY 0.680851 (1690 6460);
PAINT WHITE (1690 6460);
WIRE 16 -1 (175 6450)(1350 6450);
FORCEPROP 2 LAST SIG_NAME NCSI_BMC_RXD1_R
J 0
(465 6460);
DISPLAY 0.680851 (465 6460);
PAINT WHITE (465 6460);
FORCEPROP 2 LASTPROP $XRERR UNIQUE?
J 0
(225 6460);
DISPLAY 0.638298 (225 6460);
PAINT MONO (225 6460);
DISPLAY INVISIBLE (225 6460);
WIRE 16 -1 (175 6600)(1350 6600);
FORCEPROP 0 LAST CDS_PHYS_NET_NAME NCSI_OCP_SFF_RXD0
J 0
(240 6642);
PAINT MONO (240 6642);
DISPLAY INVISIBLE (240 6642);
FORCEPROP 2 LAST SIG_NAME NCSI_BMC_RXD0_R
J 0
(465 6610);
DISPLAY 0.680851 (465 6610);
PAINT WHITE (465 6610);
FORCEPROP 2 LASTPROP $XRERR UNIQUE?
J 0
(225 6610);
DISPLAY 0.638298 (225 6610);
PAINT MONO (225 6610);
DISPLAY INVISIBLE (225 6610);
WIRE 16 -1 (1350 6750)(175 6750);
FORCEPROP 0 LAST CDS_PHYS_NET_NAME NCSI_OCP_SFF_CRS_DV
J 0
(240 6792);
PAINT MONO (240 6792);
DISPLAY INVISIBLE (240 6792);
FORCEPROP 2 LAST SIG_NAME NCSI_BMC_CRS_DV_R
J 0
(465 6760);
DISPLAY 0.680851 (465 6760);
PAINT WHITE (465 6760);
FORCEPROP 2 LASTPROP $XRERR UNIQUE?
J 0
(225 6760);
DISPLAY 0.638298 (225 6760);
PAINT MONO (225 6760);
DISPLAY INVISIBLE (225 6760);
WIRE 16 -1 (175 5475)(2900 5475);
FORCEPROP 2 LAST SIG_NAME OCP_SFF_RBT_ARB_OUT
J 0
(465 5485);
DISPLAY 0.680851 (465 5485);
PAINT WHITE (465 5485);
WIRE 16 -1 (2900 6625)(2900 5475);
WIRE 16 -1 (3775 5475)(2900 5475);
WIRE 16 -1 (175 5175)(1350 5175);
FORCEPROP 2 LAST SIG_NAME NCSI_BMC_TXD0_R
J 0
(465 5185);
DISPLAY 0.680851 (465 5185);
PAINT WHITE (465 5185);
FORCEPROP 2 LASTPROP $XRERR UNIQUE?
J 0
(225 5185);
DISPLAY 0.638298 (225 5185);
PAINT MONO (225 5185);
DISPLAY INVISIBLE (225 5185);
WIRE 16 -1 (-1575 5325)(-625 5325);
FORCEPROP 2 LAST SIG_NAME NCSI_OCP_SFF_TX_EN
J 0
(-1535 5335);
DISPLAY 0.680851 (-1535 5335);
PAINT WHITE (-1535 5335);
WIRE 16 -1 (2550 5325)(1550 5325);
FORCEPROP 2 LAST SIG_NAME RMII_BMC_OCP_TX_EN
J 0
(1840 5335);
DISPLAY 0.680851 (1840 5335);
PAINT WHITE (1840 5335);
WIRE 16 -1 (175 5025)(1350 5025);
FORCEPROP 2 LAST SIG_NAME NCSI_BMC_TXD1_R
J 0
(465 5035);
DISPLAY 0.680851 (465 5035);
PAINT WHITE (465 5035);
FORCEPROP 2 LASTPROP $XRERR UNIQUE?
J 0
(225 5035);
DISPLAY 0.638298 (225 5035);
PAINT MONO (225 5035);
DISPLAY INVISIBLE (225 5035);
WIRE 16 -1 (-1575 5025)(-625 5025);
FORCEPROP 2 LAST SIG_NAME NCSI_OCP_SFF_TXD1
J 0
(-1535 5035);
DISPLAY 0.680851 (-1535 5035);
PAINT WHITE (-1535 5035);
WIRE 16 -1 (2925 4025)(1750 4025);
FORCEPROP 2 LAST SIG_NAME RMII_BMC_OCP_TX_EN
J 0
(1890 4035);
DISPLAY 0.680851 (1890 4035);
PAINT WHITE (1890 4035);
WIRE 16 -1 (-1575 6600)(-625 6600);
FORCEPROP 0 LAST CDS_PHYS_NET_NAME NCSI_OCP_SFF_RXD0
J 0
(-1510 6642);
PAINT MONO (-1510 6642);
DISPLAY INVISIBLE (-1510 6642);
FORCEPROP 2 LAST SIG_NAME NCSI_OCP_SFF_RXD0
J 0
(-1435 6610);
DISPLAY 0.680851 (-1435 6610);
PAINT WHITE (-1435 6610);
WIRE 16 -1 (2550 5175)(1550 5175);
FORCEPROP 2 LAST SIG_NAME RMII_BMC_OCP_TXD_0
J 0
(1840 5185);
DISPLAY 0.680851 (1840 5185);
PAINT WHITE (1840 5185);
WIRE 16 -1 (2550 5025)(1550 5025);
FORCEPROP 2 LAST SIG_NAME RMII_BMC_OCP_TXD_1
J 0
(1840 5035);
DISPLAY 0.680851 (1840 5035);
PAINT WHITE (1840 5035);
WIRE 16 -1 (-1575 6900)(-625 6900);
FORCEPROP 0 LAST CDS_PHYS_NET_NAME OCP_SFF_RBT_ARB_IN
J 0
(-1210 6942);
PAINT MONO (-1210 6942);
DISPLAY INVISIBLE (-1210 6942);
FORCEPROP 2 LAST SIG_NAME OCP_SFF_ISO1_RBT_ARB_IN
J 0
(-1435 6910);
DISPLAY 0.680851 (-1435 6910);
PAINT WHITE (-1435 6910);
WIRE 16 -1 (2925 4175)(1750 4175);
FORCEPROP 2 LAST SIG_NAME RMII_OCP_BMC_RXD_1
J 0
(1890 4185);
DISPLAY 0.680851 (1890 4185);
PAINT WHITE (1890 4185);
WIRE 16 -1 (2925 4475)(1750 4475);
FORCEPROP 2 LAST SIG_NAME RMII_OCP_BMC_CRSDV
J 0
(1890 4485);
DISPLAY 0.680851 (1890 4485);
PAINT WHITE (1890 4485);
WIRE 16 -1 (2925 4325)(1750 4325);
FORCEPROP 2 LAST SIG_NAME RMII_OCP_BMC_RXD_0
J 0
(1890 4335);
DISPLAY 0.680851 (1890 4335);
PAINT WHITE (1890 4335);
WIRE 16 -1 (2925 3725)(1750 3725);
FORCEPROP 2 LAST SIG_NAME RMII_BMC_OCP_TXD_1
J 0
(1890 3735);
DISPLAY 0.680851 (1890 3735);
PAINT WHITE (1890 3735);
WIRE 16 -1 (2925 3875)(1750 3875);
FORCEPROP 2 LAST SIG_NAME RMII_BMC_OCP_TXD_0
J 0
(1890 3885);
DISPLAY 0.680851 (1890 3885);
PAINT WHITE (1890 3885);
WIRE 16 -1 (2925 3550)(1750 3550);
FORCEPROP 2 LAST SIG_NAME RMII_BMC_OCP_RX_ER
J 0
(1890 3560);
DISPLAY 0.680851 (1890 3560);
PAINT WHITE (1890 3560);
WIRE 16 -1 (-1575 5475)(-625 5475);
FORCEPROP 2 LAST SIG_NAME OCP_SFF_ISO2_RBT_ARB_OUT
J 0
(-1535 5485);
DISPLAY 0.680851 (-1535 5485);
PAINT WHITE (-1535 5485);
WIRE 16 -1 (-1575 5175)(-625 5175);
FORCEPROP 2 LAST SIG_NAME NCSI_OCP_SFF_TXD0
J 0
(-1535 5185);
DISPLAY 0.680851 (-1535 5185);
PAINT WHITE (-1535 5185);
WIRE 16 -1 (175 5325)(1350 5325);
FORCEPROP 2 LAST SIG_NAME NCSI_BMC_TX_EN_R
J 0
(465 5335);
DISPLAY 0.680851 (465 5335);
PAINT WHITE (465 5335);
FORCEPROP 2 LASTPROP $XRERR UNIQUE?
J 0
(225 5335);
DISPLAY 0.638298 (225 5335);
PAINT MONO (225 5335);
DISPLAY INVISIBLE (225 5335);
WIRE 16 -1 (3100 2800)(1875 2800);
FORCEPROP 0 LAST CDS_PHYS_NET_NAME NCSI_OCP_SFF_CRS_DV
J 0
(2490 2842);
PAINT MONO (2490 2842);
DISPLAY INVISIBLE (2490 2842);
FORCEPROP 2 LAST SIG_NAME OCP_SFF_ISO_BIF0_EN
J 0
(2390 2810);
DISPLAY 0.680851 (2390 2810);
PAINT WHITE (2390 2810);
WIRE 16 -1 (1875 2200)(1875 2800);
WIRE 16 -1 (3100 2500)(2375 2500);
FORCEPROP 0 LAST CDS_PHYS_NET_NAME NCSI_OCP_SFF_CRS_DV
J 0
(2490 2542);
PAINT MONO (2490 2542);
DISPLAY INVISIBLE (2490 2542);
FORCEPROP 2 LAST SIG_NAME OCP_SFF_ISO_BIF2_EN
J 0
(2415 2510);
DISPLAY 0.680851 (2415 2510);
PAINT WHITE (2415 2510);
WIRE 16 -1 (2375 2200)(2375 2500);
WIRE 16 -1 (3100 2650)(2125 2650);
FORCEPROP 0 LAST CDS_PHYS_NET_NAME NCSI_OCP_SFF_CRS_DV
J 0
(2490 2692);
PAINT MONO (2490 2692);
DISPLAY INVISIBLE (2490 2692);
FORCEPROP 2 LAST SIG_NAME OCP_SFF_ISO_BIF1_EN
J 0
(2415 2660);
DISPLAY 0.680851 (2415 2660);
PAINT WHITE (2415 2660);
WIRE 16 -1 (2125 2200)(2125 2650);
WIRE 16 -1 (-1575 6450)(-625 6450);
FORCEPROP 2 LAST SIG_NAME NCSI_OCP_SFF_RXD1
J 0
(-1435 6460);
DISPLAY 0.680851 (-1435 6460);
PAINT WHITE (-1435 6460);
WIRE 16 -1 (-625 6750)(-1575 6750);
FORCEPROP 0 LAST CDS_PHYS_NET_NAME NCSI_OCP_SFF_CRS_DV
J 0
(-1510 6792);
PAINT MONO (-1510 6792);
DISPLAY INVISIBLE (-1510 6792);
FORCEPROP 2 LAST SIG_NAME NCSI_OCP_SFF_CRS_DV
J 0
(-1435 6760);
DISPLAY 0.680851 (-1435 6760);
PAINT WHITE (-1435 6760);
DOT 1 (2900 6900);
DOT 1 (400 4975);
DOT 1 (-1125 2275);
DOT 1 (-2350 2875);
DOT 1 (400 6700);
DOT 1 (400 5275);
DOT 1 (400 5125);
DOT 1 (-775 5975);
DOT 1 (400 5425);
DOT 1 (400 6550);
DOT 1 (400 6400);
DOT 1 (3625 4325);
DOT 1 (3625 4175);
DOT 1 (3625 4025);
DOT 1 (3625 3725);
DOT 1 (3625 3875);
DOT 1 (3625 3550);
DOT 1 (-775 7400);
DOT 1 (-175 4000);
DOT 1 (2900 5475);
DOT 1 (2375 1925);
DOT 1 (2125 1925);
DOT 1 (400 4000);
DOT 1 (-2075 4550);
QUIT
